# Altium SchDoc records: FPGA.SchDoc
|HEADER=Protel for Windows - Schematic Capture Binary File Version 5.0|Weight=1287|MinorVersion=4
|RECORD=31|FontIdCount=5|Size1=10|FontName1=Times New Roman|Size2=8|FontName2=Arial|Size3=10|FontName3=Arial|Size4=12|Underline4=T|FontName4=Arial|Size5=11|FontName5=Arial|UseMBCS=T|IsBOC=T|HotSpotGridOn=T|HotSpotGridSize_Frac=40000|SheetStyle=12|SystemFont=3|BorderOn=T|SheetNumberSpaceSize=12|AreaColor=16317695|SnapGridOn=T|SnapGridSize=1|VisibleGridOn=T|VisibleGridSize=10|CustomX=2338|CustomX_Frac=58268|CustomY=1653|CustomY_Frac=54331|CustomXZones=8|CustomYZones=6|CustomMarginWidth=19|CustomMarginWidth_Frac=80000|ShowTemplateGraphics=T|TemplateFileName=C:\Users\<user>\Documents\Altium\AD20\Templates\Timecard.SchDot|Display_Unit=0
|RECORD=39|IsNotAccesible=T|OwnerPartId=-1|FileName=C:\Users\<user>\Documents\Altium\AD20\Templates\Timecard.SchDot
|RECORD=4|OwnerIndex=1|OwnerPartId=-1|Location.X=1594|Location.Y=39|Color=8388608|FontID=4|Text=timingcard.com|URL=http://timingcard.com
|RECORD=6|OwnerIndex=1|IndexInSheet=1|OwnerPartId=-1|LocationCount=2|X1=1680|Y1=35|X2=1576|Y2=35
|RECORD=4|OwnerIndex=1|IndexInSheet=2|OwnerPartId=-1|Location.X=1615|Location.Y=27|Justification=4|Color=16711680|FontID=5|Text==SheetNumber
|RECORD=4|OwnerIndex=1|IndexInSheet=3|OwnerPartId=-1|Location.X=1581|Location.X_Frac=42446|Location.Y=29|Location.Y_Frac=96838|Justification=3|FontID=2|Text=SHEET
|RECORD=4|OwnerIndex=1|IndexInSheet=4|OwnerPartId=-1|Location.X=1639|Location.X_Frac=42446|Location.Y=29|Location.Y_Frac=96838|Justification=3|FontID=2|Text=OF
|RECORD=6|OwnerIndex=1|IndexInSheet=5|OwnerPartId=-1|LineWidth=1|LocationCount=2|X1=1679|X1_Frac=42446|Y1=117|Y1_Frac=96838|X2=1576|Y2=118
|RECORD=4|OwnerIndex=1|IndexInSheet=6|OwnerPartId=-1|Location.X=1659|Location.Y=27|Justification=4|Color=16711680|FontID=5|Text==SheetTotal
|RECORD=30|OwnerIndex=1|IndexInSheet=7|OwnerPartId=-1|Location.X=1578|Location.Y=65|Corner.X=1673|Corner.X_Frac=88801|Corner.Y=115|KeepAspect=T|FileName=C:\Users\<user>\Desktop\Timecard Logo\TIMECARD.jpg
|RECORD=6|OwnerIndex=1|IndexInSheet=8|OwnerPartId=-1|LineWidth=1|LocationCount=2|X1=1576|X1_Frac=3162|Y1=117|Y1_Frac=42446|X2=1576|Y2=21
|RECORD=6|OwnerIndex=1|IndexInSheet=9|OwnerPartId=-1|LocationCount=2|X1=1680|Y1=51|X2=1576|Y2=51
|RECORD=4|OwnerIndex=1|IndexInSheet=10|OwnerPartId=-1|Location.X=1581|Location.X_Frac=42446|Location.Y=56|Location.Y_Frac=96838|Justification=3|FontID=2|Text=REV
|RECORD=4|OwnerIndex=1|IndexInSheet=11|OwnerPartId=-1|Location.X=1619|Location.Y=57|Justification=3|FontID=2|Text=DATE
|RECORD=6|OwnerIndex=1|IndexInSheet=12|OwnerPartId=-1|LocationCount=2|X1=1680|Y1=65|X2=1576|Y2=65
|RECORD=4|OwnerIndex=1|IndexInSheet=13|OwnerPartId=-1|Location.X=1605|Location.Y=58|Justification=4|Color=16711680|FontID=5|Text==ProjectRevision
|RECORD=4|OwnerIndex=1|IndexInSheet=14|OwnerPartId=-1|Location.X=1659|Location.Y=58|Justification=4|Color=16711680|FontID=5|Text==ProjectDate
|RECORD=41|IndexInSheet=1|OwnerPartId=-1|Location.X=21474|Location.X_Frac=83647|Location.Y=21464|Location.Y_Frac=83647|Color=8388608|FontID=1|IsHidden=T|Text=01910|Name=Customer
|RECORD=41|IndexInSheet=2|OwnerPartId=-1|Location.X=1000|Location.Y=10|Color=8388608|FontID=1|IsHidden=T|Text=*|Name=DocStatus
|RECORD=17|IndexInSheet=3|OwnerPartId=-1|ShowNetName=T|Location.X=410|Location.Y=1008|Orientation=1|Color=128|FontID=1|Text=+5.0V
|RECORD=22|IndexInSheet=4|OwnerPartId=-1|Location.X=460|Location.Y=938|Color=255|Orientation=1|Symbol=Thin Cross|IsActive=T|SuppressAll=T
|RECORD=22|IndexInSheet=5|OwnerPartId=-1|Location.X=460|Location.Y=928|Color=255|Orientation=1|Symbol=Thin Cross|IsActive=T|SuppressAll=T
|RECORD=22|IndexInSheet=6|OwnerPartId=-1|Location.X=460|Location.Y=918|Color=255|Orientation=1|Symbol=Thin Cross|IsActive=T|SuppressAll=T
|RECORD=22|IndexInSheet=7|OwnerPartId=-1|Location.X=460|Location.Y=908|Color=255|Orientation=1|Symbol=Thin Cross|IsActive=T|SuppressAll=T
|RECORD=22|IndexInSheet=8|OwnerPartId=-1|Location.X=460|Location.Y=718|Color=255|Orientation=1|Symbol=Thin Cross|IsActive=T|SuppressAll=T
|RECORD=22|IndexInSheet=9|OwnerPartId=-1|Location.X=460|Location.Y=708|Color=255|Orientation=1|Symbol=Thin Cross|IsActive=T|SuppressAll=T
|RECORD=22|IndexInSheet=10|OwnerPartId=-1|Location.X=460|Location.Y=598|Color=255|Orientation=1|Symbol=Thin Cross|IsActive=T|SuppressAll=T
|RECORD=17|IndexInSheet=11|OwnerPartId=-1|Style=4|ShowNetName=T|Location.X=410|Location.Y=568|Orientation=3|Color=128|FontID=1|Text=GND
|RECORD=17|IndexInSheet=12|OwnerPartId=-1|ShowNetName=T|Location.X=330|Location.Y=658|Orientation=2|Color=255|FontID=1|Text=KEY2|IsCrossSheetConnector=T
|RECORD=17|IndexInSheet=13|OwnerPartId=-1|ShowNetName=T|Location.X=330|Location.Y=638|Orientation=2|Color=255|FontID=1|Text=LED4|IsCrossSheetConnector=T
|RECORD=17|IndexInSheet=14|OwnerPartId=-1|ShowNetName=T|Location.X=330|Location.Y=628|Orientation=2|Color=255|FontID=1|Text=LED3|IsCrossSheetConnector=T
|RECORD=17|IndexInSheet=15|OwnerPartId=-1|ShowNetName=T|Location.X=330|Location.Y=618|Orientation=2|Color=255|FontID=1|Text=LED2|IsCrossSheetConnector=T
|RECORD=17|IndexInSheet=16|OwnerPartId=-1|ShowNetName=T|Location.X=330|Location.Y=608|Orientation=2|Color=255|FontID=1|Text=LED1|IsCrossSheetConnector=T
|RECORD=17|IndexInSheet=17|OwnerPartId=-1|ShowNetName=T|Location.X=600|Location.Y=1008|Orientation=1|Color=128|FontID=1|Text=+5.0V
|RECORD=22|IndexInSheet=18|OwnerPartId=-1|Location.X=580|Location.Y=938|Color=255|Orientation=1|Symbol=Thin Cross|IsActive=T|SuppressAll=T
|RECORD=22|IndexInSheet=19|OwnerPartId=-1|Location.X=580|Location.Y=928|Color=255|Orientation=1|Symbol=Thin Cross|IsActive=T|SuppressAll=T
|RECORD=22|IndexInSheet=20|OwnerPartId=-1|Location.X=580|Location.Y=738|Color=255|Orientation=1|Symbol=Thin Cross|IsActive=T|SuppressAll=T
|RECORD=22|IndexInSheet=21|OwnerPartId=-1|Location.X=580|Location.Y=668|Color=255|Orientation=1|Symbol=Thin Cross|IsActive=T|SuppressAll=T
|RECORD=22|IndexInSheet=22|OwnerPartId=-1|Location.X=580|Location.Y=658|Color=255|Orientation=1|Symbol=Thin Cross|IsActive=T|SuppressAll=T
|RECORD=22|IndexInSheet=23|OwnerPartId=-1|Location.X=580|Location.Y=638|Color=255|Orientation=1|Symbol=Thin Cross|IsActive=T|SuppressAll=T
|RECORD=22|IndexInSheet=24|OwnerPartId=-1|Location.X=580|Location.Y=628|Color=255|Orientation=1|Symbol=Thin Cross|IsActive=T|SuppressAll=T
|RECORD=22|IndexInSheet=25|OwnerPartId=-1|Location.X=580|Location.Y=618|Color=255|Orientation=1|Symbol=Thin Cross|IsActive=T|SuppressAll=T
|RECORD=22|IndexInSheet=26|OwnerPartId=-1|Location.X=580|Location.Y=608|Color=255|Orientation=1|Symbol=Thin Cross|IsActive=T|SuppressAll=T
|RECORD=22|IndexInSheet=27|OwnerPartId=-1|Location.X=580|Location.Y=598|Color=255|Orientation=1|Symbol=Thin Cross|IsActive=T|SuppressAll=T
|RECORD=17|IndexInSheet=28|OwnerPartId=-1|Style=4|ShowNetName=T|Location.X=600|Location.Y=568|Orientation=3|Color=128|FontID=1|Text=GND
|RECORD=17|IndexInSheet=29|OwnerPartId=-1|ShowNetName=T|Location.X=640|Location.Y=888|Color=255|FontID=1|Text=GPS1_RST|IsCrossSheetConnector=T
|RECORD=17|IndexInSheet=30|OwnerPartId=-1|ShowNetName=T|Location.X=640|Location.Y=838|Color=255|FontID=1|Text=GPS1_TP1|IsCrossSheetConnector=T
|RECORD=17|IndexInSheet=31|OwnerPartId=-1|ShowNetName=T|Location.X=640|Location.Y=828|Color=255|FontID=1|Text=GPS1_TP2|IsCrossSheetConnector=T
|RECORD=17|IndexInSheet=32|OwnerPartId=-1|Style=4|ShowNetName=T|Location.X=1130|Location.Y=568|Orientation=3|Color=128|FontID=1|Text=GND
|RECORD=17|IndexInSheet=33|OwnerPartId=-1|ShowNetName=T|Location.X=1060|Location.Y=598|Orientation=2|Color=255|FontID=1|Text=GPS1_RX|IsCrossSheetConnector=T
|RECORD=17|IndexInSheet=34|OwnerPartId=-1|ShowNetName=T|Location.X=1060|Location.Y=818|Orientation=2|Color=255|FontID=1|Text=MAC_ALARM|IsCrossSheetConnector=T
|RECORD=17|IndexInSheet=35|OwnerPartId=-1|ShowNetName=T|Location.X=1060|Location.Y=808|Orientation=2|Color=255|FontID=1|Text=MAC_BITE|IsCrossSheetConnector=T
|RECORD=17|IndexInSheet=36|OwnerPartId=-1|ShowNetName=T|Location.X=1060|Location.Y=828|Orientation=2|Color=255|FontID=1|Text=MAC_FREQ_CTRL|IsCrossSheetConnector=T
|RECORD=17|IndexInSheet=37|OwnerPartId=-1|ShowNetName=T|Location.X=1060|Location.Y=758|Orientation=2|Color=255|FontID=1|Text=FPGA_MAC_PPS_IN0-|IsCrossSheetConnector=T
|RECORD=17|IndexInSheet=38|OwnerPartId=-1|ShowNetName=T|Location.X=1060|Location.Y=728|Orientation=2|Color=255|FontID=1|Text=FPGA_MAC_PPS_IN1-|IsCrossSheetConnector=T
|RECORD=17|IndexInSheet=39|OwnerPartId=-1|ShowNetName=T|Location.X=1060|Location.Y=778|Orientation=2|Color=255|FontID=1|Text=FPGA_MAC_PPS_OUT-|IsCrossSheetConnector=T
|RECORD=17|IndexInSheet=40|OwnerPartId=-1|ShowNetName=T|Location.X=1060|Location.Y=938|Orientation=2|Color=255|FontID=1|Text=MAC_RF_OUT|IsCrossSheetConnector=T
|RECORD=17|IndexInSheet=41|OwnerPartId=-1|ShowNetName=T|Location.X=1060|Location.Y=688|Orientation=2|Color=255|FontID=1|Text=SDA|IsCrossSheetConnector=T
|RECORD=17|IndexInSheet=42|OwnerPartId=-1|ShowNetName=T|Location.X=1060|Location.Y=658|Orientation=2|Color=255|FontID=1|Text=SCL|IsCrossSheetConnector=T
|RECORD=17|IndexInSheet=43|OwnerPartId=-1|Style=4|ShowNetName=T|Location.X=1320|Location.Y=568|Orientation=3|Color=128|FontID=1|Text=GND
|RECORD=17|IndexInSheet=44|OwnerPartId=-1|ShowNetName=T|Location.X=1350|Location.Y=598|Color=255|FontID=1|Text=GPS1_TX|IsCrossSheetConnector=T
|RECORD=17|IndexInSheet=45|OwnerPartId=-1|ShowNetName=T|Location.X=1350|Location.Y=858|Color=255|FontID=1|Text=MAC_RX|IsCrossSheetConnector=T
|RECORD=17|IndexInSheet=46|OwnerPartId=-1|ShowNetName=T|Location.X=1350|Location.Y=868|Color=255|FontID=1|Text=MAC_TX|IsCrossSheetConnector=T
|RECORD=17|IndexInSheet=47|OwnerPartId=-1|ShowNetName=T|Location.X=1350|Location.Y=638|Color=255|FontID=1|Text=MAC_USB+|IsCrossSheetConnector=T
|RECORD=17|IndexInSheet=48|OwnerPartId=-1|ShowNetName=T|Location.X=1350|Location.Y=628|Color=255|FontID=1|Text=MAC_USB-|IsCrossSheetConnector=T
|RECORD=17|IndexInSheet=49|OwnerPartId=-1|ShowNetName=T|Location.X=1350|Location.Y=958|Color=255|FontID=1|Text=MAC_USB_PWR|IsCrossSheetConnector=T
|RECORD=17|IndexInSheet=50|OwnerPartId=-1|Style=4|ShowNetName=T|Location.X=400|Location.Y=68|Orientation=3|Color=128|FontID=1|Text=GND
|RECORD=22|IndexInSheet=51|OwnerPartId=-1|Location.X=460|Location.Y=128|Color=255|Orientation=1|Symbol=Thin Cross|IsActive=T|SuppressAll=T
|RECORD=17|IndexInSheet=52|OwnerPartId=-1|ShowNetName=T|Location.X=320|Location.Y=398|Orientation=2|Color=255|FontID=1|Text=PCIE_PERST|IsCrossSheetConnector=T
|RECORD=17|IndexInSheet=53|OwnerPartId=-1|ShowNetName=T|Location.X=320|Location.Y=388|Orientation=2|Color=255|FontID=1|Text=KEY1|IsCrossSheetConnector=T
|RECORD=17|IndexInSheet=54|OwnerPartId=-1|ShowNetName=T|Location.X=320|Location.Y=118|Orientation=2|Color=255|FontID=1|Text=FPGA_TCK|IsCrossSheetConnector=T
|RECORD=17|IndexInSheet=55|OwnerPartId=-1|ShowNetName=T|Location.X=320|Location.Y=108|Orientation=2|Color=255|FontID=1|Text=FPGA_TDO|IsCrossSheetConnector=T
|RECORD=17|IndexInSheet=56|OwnerPartId=-1|Style=4|ShowNetName=T|Location.X=620|Location.Y=68|Orientation=3|Color=128|FontID=1|Text=GND
|RECORD=22|IndexInSheet=57|OwnerPartId=-1|Location.X=580|Location.Y=128|Color=255|Orientation=1|Symbol=Thin Cross|IsActive=T|SuppressAll=T
|RECORD=17|IndexInSheet=58|OwnerPartId=-1|ShowNetName=T|Location.X=690|Location.Y=118|Color=255|FontID=1|Text=FPGA_TDI|IsCrossSheetConnector=T
|RECORD=17|IndexInSheet=59|OwnerPartId=-1|ShowNetName=T|Location.X=690|Location.Y=108|Color=255|FontID=1|Text=FPGA_TMS|IsCrossSheetConnector=T
|RECORD=22|IndexInSheet=60|OwnerPartId=-1|Location.X=1160|Location.Y=498|Color=255|Orientation=1|Symbol=Thin Cross|IsActive=T|SuppressAll=T
|RECORD=22|IndexInSheet=61|OwnerPartId=-1|Location.X=1160|Location.Y=488|Color=255|Orientation=1|Symbol=Thin Cross|IsActive=T|SuppressAll=T
|RECORD=22|IndexInSheet=62|OwnerPartId=-1|Location.X=1160|Location.Y=478|Color=255|Orientation=1|Symbol=Thin Cross|IsActive=T|SuppressAll=T
|RECORD=22|IndexInSheet=63|OwnerPartId=-1|Location.X=1160|Location.Y=468|Color=255|Orientation=1|Symbol=Thin Cross|IsActive=T|SuppressAll=T
|RECORD=22|IndexInSheet=64|OwnerPartId=-1|Location.X=1160|Location.Y=448|Color=255|Orientation=1|Symbol=Thin Cross|IsActive=T|SuppressAll=T
|RECORD=22|IndexInSheet=65|OwnerPartId=-1|Location.X=1160|Location.Y=438|Color=255|Orientation=1|Symbol=Thin Cross|IsActive=T|SuppressAll=T
|RECORD=22|IndexInSheet=66|OwnerPartId=-1|Location.X=1160|Location.Y=108|Color=255|Orientation=1|Symbol=Thin Cross|IsActive=T|SuppressAll=T
|RECORD=17|IndexInSheet=67|OwnerPartId=-1|Style=4|ShowNetName=T|Location.X=1110|Location.Y=78|Orientation=3|Color=128|FontID=1|Text=GND
|RECORD=17|IndexInSheet=68|OwnerPartId=-1|ShowNetName=T|Location.X=1060|Location.Y=418|Orientation=2|Color=255|FontID=1|Text=PCIE_TX3_P|IsCrossSheetConnector=T
|RECORD=17|IndexInSheet=69|OwnerPartId=-1|ShowNetName=T|Location.X=1060|Location.Y=408|Orientation=2|Color=255|FontID=1|Text=PCIE_TX3_N|IsCrossSheetConnector=T
|RECORD=17|IndexInSheet=70|OwnerPartId=-1|ShowNetName=T|Location.X=1060|Location.Y=388|Orientation=2|Color=255|FontID=1|Text=PCIE_RX3_P|IsCrossSheetConnector=T
|RECORD=17|IndexInSheet=71|OwnerPartId=-1|ShowNetName=T|Location.X=1060|Location.Y=378|Orientation=2|Color=255|FontID=1|Text=PCIE_RX3_N|IsCrossSheetConnector=T
|RECORD=17|IndexInSheet=72|OwnerPartId=-1|ShowNetName=T|Location.X=1060|Location.Y=358|Orientation=2|Color=255|FontID=1|Text=PCIE_TX0_P|IsCrossSheetConnector=T
|RECORD=17|IndexInSheet=73|OwnerPartId=-1|ShowNetName=T|Location.X=1060|Location.Y=348|Orientation=2|Color=255|FontID=1|Text=PCIE_TX0_N|IsCrossSheetConnector=T
|RECORD=17|IndexInSheet=74|OwnerPartId=-1|ShowNetName=T|Location.X=1060|Location.Y=328|Orientation=2|Color=255|FontID=1|Text=PCIE_RX0_P|IsCrossSheetConnector=T
|RECORD=17|IndexInSheet=75|OwnerPartId=-1|ShowNetName=T|Location.X=1060|Location.Y=318|Orientation=2|Color=255|FontID=1|Text=PCIE_RX0_N|IsCrossSheetConnector=T
|RECORD=43|IndexInSheet=76|OwnerPartId=-1|Location.X=1070|Location.Y=418|Color=255|Name=DIFFPAIR
|RECORD=41|OwnerIndex=92|OwnerPartId=-1|Location.X=1070|Location.Y=418|Color=8388608|FontID=1|IsHidden=T|Text=True|Name=DifferentialPair
|RECORD=43|IndexInSheet=77|OwnerPartId=-1|Location.X=1070|Location.Y=408|Color=255|Name=DIFFPAIR
|RECORD=41|OwnerIndex=94|OwnerPartId=-1|Location.X=1070|Location.Y=408|Color=8388608|FontID=1|IsHidden=T|Text=True|Name=DifferentialPair
|RECORD=43|IndexInSheet=78|OwnerPartId=-1|Location.X=1070|Location.Y=388|Color=255|Name=DIFFPAIR
|RECORD=41|OwnerIndex=96|OwnerPartId=-1|Location.X=1070|Location.Y=388|Color=8388608|FontID=1|IsHidden=T|Text=True|Name=DifferentialPair
|RECORD=43|IndexInSheet=79|OwnerPartId=-1|Location.X=1070|Location.Y=378|Color=255|Name=DIFFPAIR
|RECORD=41|OwnerIndex=98|OwnerPartId=-1|Location.X=1070|Location.Y=378|Color=8388608|FontID=1|IsHidden=T|Text=True|Name=DifferentialPair
|RECORD=43|IndexInSheet=80|OwnerPartId=-1|Location.X=1070|Location.Y=358|Color=255|Name=DIFFPAIR
|RECORD=41|OwnerIndex=100|OwnerPartId=-1|Location.X=1070|Location.Y=358|Color=8388608|FontID=1|IsHidden=T|Text=True|Name=DifferentialPair
|RECORD=43|IndexInSheet=81|OwnerPartId=-1|Location.X=1070|Location.Y=348|Color=255|Name=DIFFPAIR
|RECORD=41|OwnerIndex=102|OwnerPartId=-1|Location.X=1070|Location.Y=348|Color=8388608|FontID=1|IsHidden=T|Text=True|Name=DifferentialPair
|RECORD=43|IndexInSheet=82|OwnerPartId=-1|Location.X=1070|Location.Y=328|Color=255|Name=DIFFPAIR
|RECORD=41|OwnerIndex=104|OwnerPartId=-1|Location.X=1070|Location.Y=328|Color=8388608|FontID=1|IsHidden=T|Text=True|Name=DifferentialPair
|RECORD=43|IndexInSheet=83|OwnerPartId=-1|Location.X=1070|Location.Y=318|Color=255|Name=DIFFPAIR
|RECORD=41|OwnerIndex=106|OwnerPartId=-1|Location.X=1070|Location.Y=318|Color=8388608|FontID=1|IsHidden=T|Text=True|Name=DifferentialPair
|RECORD=22|IndexInSheet=84|OwnerPartId=-1|Location.X=1280|Location.Y=498|Color=255|Orientation=1|Symbol=Thin Cross|IsActive=T|SuppressAll=T
|RECORD=22|IndexInSheet=85|OwnerPartId=-1|Location.X=1280|Location.Y=488|Color=255|Orientation=1|Symbol=Thin Cross|IsActive=T|SuppressAll=T
|RECORD=22|IndexInSheet=86|OwnerPartId=-1|Location.X=1280|Location.Y=478|Color=255|Orientation=1|Symbol=Thin Cross|IsActive=T|SuppressAll=T
|RECORD=22|IndexInSheet=87|OwnerPartId=-1|Location.X=1280|Location.Y=468|Color=255|Orientation=1|Symbol=Thin Cross|IsActive=T|SuppressAll=T
|RECORD=22|IndexInSheet=88|OwnerPartId=-1|Location.X=1280|Location.Y=108|Color=255|Orientation=1|Symbol=Thin Cross|IsActive=T|SuppressAll=T
|RECORD=17|IndexInSheet=89|OwnerPartId=-1|Style=4|ShowNetName=T|Location.X=1310|Location.Y=78|Orientation=3|Color=128|FontID=1|Text=GND
|RECORD=17|IndexInSheet=90|OwnerPartId=-1|ShowNetName=T|Location.X=1360|Location.Y=448|Color=255|FontID=1|Text=PCIE_TX2_P|IsCrossSheetConnector=T
|RECORD=17|IndexInSheet=91|OwnerPartId=-1|ShowNetName=T|Location.X=1360|Location.Y=438|Color=255|FontID=1|Text=PCIE_TX2_N|IsCrossSheetConnector=T
|RECORD=17|IndexInSheet=92|OwnerPartId=-1|ShowNetName=T|Location.X=1360|Location.Y=418|Color=255|FontID=1|Text=PCIE_RX2_P|IsCrossSheetConnector=T
|RECORD=17|IndexInSheet=93|OwnerPartId=-1|ShowNetName=T|Location.X=1360|Location.Y=408|Color=255|FontID=1|Text=PCIE_RX2_N|IsCrossSheetConnector=T
|RECORD=17|IndexInSheet=94|OwnerPartId=-1|ShowNetName=T|Location.X=1360|Location.Y=388|Color=255|FontID=1|Text=PCIE_TX1_P|IsCrossSheetConnector=T
|RECORD=17|IndexInSheet=95|OwnerPartId=-1|ShowNetName=T|Location.X=1360|Location.Y=378|Color=255|FontID=1|Text=PCIE_TX1_N|IsCrossSheetConnector=T
|RECORD=17|IndexInSheet=96|OwnerPartId=-1|ShowNetName=T|Location.X=1360|Location.Y=358|Color=255|FontID=1|Text=PCIE_RX1_P|IsCrossSheetConnector=T
|RECORD=17|IndexInSheet=97|OwnerPartId=-1|ShowNetName=T|Location.X=1360|Location.Y=348|Color=255|FontID=1|Text=PCIE_RX1_N|IsCrossSheetConnector=T
|RECORD=17|IndexInSheet=98|OwnerPartId=-1|ShowNetName=T|Location.X=1360|Location.Y=328|Color=255|FontID=1|Text=PCIE_CLK_P|IsCrossSheetConnector=T
|RECORD=17|IndexInSheet=99|OwnerPartId=-1|ShowNetName=T|Location.X=1360|Location.Y=318|Color=255|FontID=1|Text=PCIE_CLK_N|IsCrossSheetConnector=T
|RECORD=43|IndexInSheet=100|OwnerPartId=-1|Location.X=1330|Location.Y=448|Color=255|Name=DIFFPAIR
|RECORD=41|OwnerIndex=124|OwnerPartId=-1|Location.X=1330|Location.Y=448|Color=8388608|FontID=1|IsHidden=T|Text=True|Name=DifferentialPair
|RECORD=43|IndexInSheet=101|OwnerPartId=-1|Location.X=1330|Location.Y=438|Color=255|Name=DIFFPAIR
|RECORD=41|OwnerIndex=126|OwnerPartId=-1|Location.X=1330|Location.Y=438|Color=8388608|FontID=1|IsHidden=T|Text=True|Name=DifferentialPair
|RECORD=43|IndexInSheet=102|OwnerPartId=-1|Location.X=1330|Location.Y=418|Color=255|Name=DIFFPAIR
|RECORD=41|OwnerIndex=128|OwnerPartId=-1|Location.X=1330|Location.Y=418|Color=8388608|FontID=1|IsHidden=T|Text=True|Name=DifferentialPair
|RECORD=43|IndexInSheet=103|OwnerPartId=-1|Location.X=1330|Location.Y=408|Color=255|Name=DIFFPAIR
|RECORD=41|OwnerIndex=130|OwnerPartId=-1|Location.X=1330|Location.Y=408|Color=8388608|FontID=1|IsHidden=T|Text=True|Name=DifferentialPair
|RECORD=43|IndexInSheet=104|OwnerPartId=-1|Location.X=1330|Location.Y=388|Color=255|Name=DIFFPAIR
|RECORD=41|OwnerIndex=132|OwnerPartId=-1|Location.X=1330|Location.Y=388|Color=8388608|FontID=1|IsHidden=T|Text=True|Name=DifferentialPair
|RECORD=43|IndexInSheet=105|OwnerPartId=-1|Location.X=1330|Location.Y=378|Color=255|Name=DIFFPAIR
|RECORD=41|OwnerIndex=134|OwnerPartId=-1|Location.X=1330|Location.Y=378|Color=8388608|FontID=1|IsHidden=T|Text=True|Name=DifferentialPair
|RECORD=43|IndexInSheet=106|OwnerPartId=-1|Location.X=1330|Location.Y=358|Color=255|Name=DIFFPAIR
|RECORD=41|OwnerIndex=136|OwnerPartId=-1|Location.X=1330|Location.Y=358|Color=8388608|FontID=1|IsHidden=T|Text=True|Name=DifferentialPair
|RECORD=43|IndexInSheet=107|OwnerPartId=-1|Location.X=1330|Location.Y=348|Color=255|Name=DIFFPAIR
|RECORD=41|OwnerIndex=138|OwnerPartId=-1|Location.X=1330|Location.Y=348|Color=8388608|FontID=1|IsHidden=T|Text=True|Name=DifferentialPair
|RECORD=43|IndexInSheet=108|OwnerPartId=-1|Location.X=1330|Location.Y=328|Color=255|Name=DIFFPAIR
|RECORD=41|OwnerIndex=140|OwnerPartId=-1|Location.X=1330|Location.Y=328|Color=8388608|FontID=1|IsHidden=T|Text=True|Name=DifferentialPair
|RECORD=43|IndexInSheet=109|OwnerPartId=-1|Location.X=1330|Location.Y=318|Color=255|Name=DIFFPAIR
|RECORD=41|OwnerIndex=142|OwnerPartId=-1|Location.X=1330|Location.Y=318|Color=8388608|FontID=1|IsHidden=T|Text=True|Name=DifferentialPair
|RECORD=22|IndexInSheet=110|OwnerPartId=-1|Location.X=460|Location.Y=838|Color=255|Orientation=1|Symbol=Thin Cross|IsActive=T|SuppressAll=T
|RECORD=22|IndexInSheet=111|OwnerPartId=-1|Location.X=460|Location.Y=828|Color=255|Orientation=1|Symbol=Thin Cross|IsActive=T|SuppressAll=T
|RECORD=22|IndexInSheet=112|OwnerPartId=-1|Location.X=460|Location.Y=808|Color=255|Orientation=1|Symbol=Thin Cross|IsActive=T|SuppressAll=T
|RECORD=22|IndexInSheet=113|OwnerPartId=-1|Location.X=460|Location.Y=788|Color=255|Orientation=1|Symbol=Thin Cross|IsActive=T|SuppressAll=T
|RECORD=22|IndexInSheet=114|OwnerPartId=-1|Location.X=460|Location.Y=758|Color=255|Orientation=1|Symbol=Thin Cross|IsActive=T|SuppressAll=T
|RECORD=22|IndexInSheet=115|OwnerPartId=-1|Location.X=460|Location.Y=738|Color=255|Orientation=1|Symbol=Thin Cross|IsActive=T|SuppressAll=T
|RECORD=22|IndexInSheet=116|OwnerPartId=-1|Location.X=460|Location.Y=728|Color=255|Orientation=1|Symbol=Thin Cross|IsActive=T|SuppressAll=T
|RECORD=22|IndexInSheet=117|OwnerPartId=-1|Location.X=460|Location.Y=688|Color=255|Orientation=1|Symbol=Thin Cross|IsActive=T|SuppressAll=T
|RECORD=22|IndexInSheet=118|OwnerPartId=-1|Location.X=460|Location.Y=678|Color=255|Orientation=1|Symbol=Thin Cross|IsActive=T|SuppressAll=T
|RECORD=22|IndexInSheet=119|OwnerPartId=-1|Location.X=460|Location.Y=668|Color=255|Orientation=1|Symbol=Thin Cross|IsActive=T|SuppressAll=T
|RECORD=22|IndexInSheet=120|OwnerPartId=-1|Location.X=460|Location.Y=588|Color=255|Orientation=1|Symbol=Thin Cross|IsActive=T|SuppressAll=T
|RECORD=22|IndexInSheet=121|OwnerPartId=-1|Location.X=460|Location.Y=578|Color=255|Orientation=1|Symbol=Thin Cross|IsActive=T|SuppressAll=T
|RECORD=22|IndexInSheet=122|OwnerPartId=-1|Location.X=580|Location.Y=588|Color=255|Orientation=1|Symbol=Thin Cross|IsActive=T|SuppressAll=T
|RECORD=22|IndexInSheet=123|OwnerPartId=-1|Location.X=580|Location.Y=578|Color=255|Orientation=1|Symbol=Thin Cross|IsActive=T|SuppressAll=T
|RECORD=22|IndexInSheet=124|OwnerPartId=-1|Location.X=580|Location.Y=708|Color=255|Orientation=1|Symbol=Thin Cross|IsActive=T|SuppressAll=T
|RECORD=22|IndexInSheet=125|OwnerPartId=-1|Location.X=580|Location.Y=788|Color=255|Orientation=1|Symbol=Thin Cross|IsActive=T|SuppressAll=T
|RECORD=22|IndexInSheet=126|OwnerPartId=-1|Location.X=580|Location.Y=808|Color=255|Orientation=1|Symbol=Thin Cross|IsActive=T|SuppressAll=T
|RECORD=22|IndexInSheet=127|OwnerPartId=-1|Location.X=580|Location.Y=818|Color=255|Orientation=1|Symbol=Thin Cross|IsActive=T|SuppressAll=T
|RECORD=22|IndexInSheet=128|OwnerPartId=-1|Location.X=580|Location.Y=858|Color=255|Orientation=1|Symbol=Thin Cross|IsActive=T|SuppressAll=T
|RECORD=22|IndexInSheet=129|OwnerPartId=-1|Location.X=580|Location.Y=868|Color=255|Orientation=1|Symbol=Thin Cross|IsActive=T|SuppressAll=T
|RECORD=22|IndexInSheet=130|OwnerPartId=-1|Location.X=580|Location.Y=878|Color=255|Orientation=1|Symbol=Thin Cross|IsActive=T|SuppressAll=T
|RECORD=22|IndexInSheet=131|OwnerPartId=-1|Location.X=580|Location.Y=908|Color=255|Orientation=1|Symbol=Thin Cross|IsActive=T|SuppressAll=T
|RECORD=22|IndexInSheet=132|OwnerPartId=-1|Location.X=580|Location.Y=918|Color=255|Orientation=1|Symbol=Thin Cross|IsActive=T|SuppressAll=T
|RECORD=22|IndexInSheet=133|OwnerPartId=-1|Location.X=1170|Location.Y=988|Color=255|Orientation=1|Symbol=Thin Cross|IsActive=T|SuppressAll=T
|RECORD=22|IndexInSheet=134|OwnerPartId=-1|Location.X=1170|Location.Y=968|Color=255|Orientation=1|Symbol=Thin Cross|IsActive=T|SuppressAll=T
|RECORD=22|IndexInSheet=135|OwnerPartId=-1|Location.X=1170|Location.Y=978|Color=255|Orientation=1|Symbol=Thin Cross|IsActive=T|SuppressAll=T
|RECORD=22|IndexInSheet=136|OwnerPartId=-1|Location.X=1170|Location.Y=958|Color=255|Orientation=1|Symbol=Thin Cross|IsActive=T|SuppressAll=T
|RECORD=22|IndexInSheet=137|OwnerPartId=-1|Location.X=1290|Location.Y=978|Color=255|Orientation=1|Symbol=Thin Cross|IsActive=T|SuppressAll=T
|RECORD=22|IndexInSheet=138|OwnerPartId=-1|Location.X=1290|Location.Y=988|Color=255|Orientation=1|Symbol=Thin Cross|IsActive=T|SuppressAll=T
|RECORD=22|IndexInSheet=139|OwnerPartId=-1|Location.X=1290|Location.Y=938|Color=255|Orientation=1|Symbol=Thin Cross|IsActive=T|SuppressAll=T
|RECORD=22|IndexInSheet=140|OwnerPartId=-1|Location.X=1290|Location.Y=928|Color=255|Orientation=1|Symbol=Thin Cross|IsActive=T|SuppressAll=T
|RECORD=22|IndexInSheet=141|OwnerPartId=-1|Location.X=1290|Location.Y=888|Color=255|Orientation=1|Symbol=Thin Cross|IsActive=T|SuppressAll=T
|RECORD=22|IndexInSheet=142|OwnerPartId=-1|Location.X=1290|Location.Y=878|Color=255|Orientation=1|Symbol=Thin Cross|IsActive=T|SuppressAll=T
|RECORD=22|IndexInSheet=143|OwnerPartId=-1|Location.X=1290|Location.Y=838|Color=255|Orientation=1|Symbol=Thin Cross|IsActive=T|SuppressAll=T
|RECORD=22|IndexInSheet=144|OwnerPartId=-1|Location.X=1290|Location.Y=818|Color=255|Orientation=1|Symbol=Thin Cross|IsActive=T|SuppressAll=T
|RECORD=22|IndexInSheet=145|OwnerPartId=-1|Location.X=1290|Location.Y=808|Color=255|Orientation=1|Symbol=Thin Cross|IsActive=T|SuppressAll=T
|RECORD=22|IndexInSheet=146|OwnerPartId=-1|Location.X=1290|Location.Y=788|Color=255|Orientation=1|Symbol=Thin Cross|IsActive=T|SuppressAll=T
|RECORD=22|IndexInSheet=147|OwnerPartId=-1|Location.X=1290|Location.Y=778|Color=255|Orientation=1|Symbol=Thin Cross|IsActive=T|SuppressAll=T
|RECORD=22|IndexInSheet=148|OwnerPartId=-1|Location.X=1290|Location.Y=778|Color=255|Orientation=1|Symbol=Thin Cross|IsActive=T|SuppressAll=T
|RECORD=22|IndexInSheet=149|OwnerPartId=-1|Location.X=1290|Location.Y=768|Color=255|Orientation=1|Symbol=Thin Cross|IsActive=T|SuppressAll=T
|RECORD=22|IndexInSheet=150|OwnerPartId=-1|Location.X=1290|Location.Y=758|Color=255|Orientation=1|Symbol=Thin Cross|IsActive=T|SuppressAll=T
|RECORD=22|IndexInSheet=151|OwnerPartId=-1|Location.X=1170|Location.Y=718|Color=255|Orientation=1|Symbol=Thin Cross|IsActive=T|SuppressAll=T
|RECORD=22|IndexInSheet=152|OwnerPartId=-1|Location.X=1170|Location.Y=708|Color=255|Orientation=1|Symbol=Thin Cross|IsActive=T|SuppressAll=T
|RECORD=22|IndexInSheet=153|OwnerPartId=-1|Location.X=1290|Location.Y=738|Color=255|Orientation=1|Symbol=Thin Cross|IsActive=T|SuppressAll=T
|RECORD=22|IndexInSheet=154|OwnerPartId=-1|Location.X=1290|Location.Y=728|Color=255|Orientation=1|Symbol=Thin Cross|IsActive=T|SuppressAll=T
|RECORD=22|IndexInSheet=155|OwnerPartId=-1|Location.X=1290|Location.Y=718|Color=255|Orientation=1|Symbol=Thin Cross|IsActive=T|SuppressAll=T
|RECORD=22|IndexInSheet=156|OwnerPartId=-1|Location.X=1290|Location.Y=708|Color=255|Orientation=1|Symbol=Thin Cross|IsActive=T|SuppressAll=T
|RECORD=22|IndexInSheet=157|OwnerPartId=-1|Location.X=1290|Location.Y=688|Color=255|Orientation=1|Symbol=Thin Cross|IsActive=T|SuppressAll=T
|RECORD=22|IndexInSheet=158|OwnerPartId=-1|Location.X=1290|Location.Y=668|Color=255|Orientation=1|Symbol=Thin Cross|IsActive=T|SuppressAll=T
|RECORD=22|IndexInSheet=159|OwnerPartId=-1|Location.X=1290|Location.Y=658|Color=255|Orientation=1|Symbol=Thin Cross|IsActive=T|SuppressAll=T
|RECORD=22|IndexInSheet=160|OwnerPartId=-1|Location.X=1170|Location.Y=678|Color=255|Orientation=1|Symbol=Thin Cross|IsActive=T|SuppressAll=T
|RECORD=22|IndexInSheet=161|OwnerPartId=-1|Location.X=1170|Location.Y=668|Color=255|Orientation=1|Symbol=Thin Cross|IsActive=T|SuppressAll=T
|RECORD=22|IndexInSheet=162|OwnerPartId=-1|Location.X=1170|Location.Y=628|Color=255|Orientation=1|Symbol=Thin Cross|IsActive=T|SuppressAll=T
|RECORD=22|IndexInSheet=163|OwnerPartId=-1|Location.X=1170|Location.Y=618|Color=255|Orientation=1|Symbol=Thin Cross|IsActive=T|SuppressAll=T
|RECORD=22|IndexInSheet=164|OwnerPartId=-1|Location.X=1290|Location.Y=618|Color=255|Orientation=1|Symbol=Thin Cross|IsActive=T|SuppressAll=T
|RECORD=22|IndexInSheet=165|OwnerPartId=-1|Location.X=1290|Location.Y=608|Color=255|Orientation=1|Symbol=Thin Cross|IsActive=T|SuppressAll=T
|RECORD=22|IndexInSheet=166|OwnerPartId=-1|Location.X=1290|Location.Y=588|Color=255|Orientation=1|Symbol=Thin Cross|IsActive=T|SuppressAll=T
|RECORD=22|IndexInSheet=167|OwnerPartId=-1|Location.X=1290|Location.Y=578|Color=255|Orientation=1|Symbol=Thin Cross|IsActive=T|SuppressAll=T
|RECORD=22|IndexInSheet=168|OwnerPartId=-1|Location.X=1170|Location.Y=588|Color=255|Orientation=1|Symbol=Thin Cross|IsActive=T|SuppressAll=T
|RECORD=22|IndexInSheet=169|OwnerPartId=-1|Location.X=1170|Location.Y=578|Color=255|Orientation=1|Symbol=Thin Cross|IsActive=T|SuppressAll=T
|RECORD=22|IndexInSheet=170|OwnerPartId=-1|Location.X=1280|Location.Y=428|Color=255|Orientation=1|Symbol=Thin Cross|IsActive=T|SuppressAll=T
|RECORD=22|IndexInSheet=171|OwnerPartId=-1|Location.X=1280|Location.Y=398|Color=255|Orientation=1|Symbol=Thin Cross|IsActive=T|SuppressAll=T
|RECORD=22|IndexInSheet=172|OwnerPartId=-1|Location.X=1280|Location.Y=368|Color=255|Orientation=1|Symbol=Thin Cross|IsActive=T|SuppressAll=T
|RECORD=22|IndexInSheet=173|OwnerPartId=-1|Location.X=1280|Location.Y=338|Color=255|Orientation=1|Symbol=Thin Cross|IsActive=T|SuppressAll=T
|RECORD=22|IndexInSheet=174|OwnerPartId=-1|Location.X=1280|Location.Y=298|Color=255|Orientation=1|Symbol=Thin Cross|IsActive=T|SuppressAll=T
|RECORD=22|IndexInSheet=175|OwnerPartId=-1|Location.X=1280|Location.Y=288|Color=255|Orientation=1|Symbol=Thin Cross|IsActive=T|SuppressAll=T
|RECORD=22|IndexInSheet=176|OwnerPartId=-1|Location.X=1280|Location.Y=278|Color=255|Orientation=1|Symbol=Thin Cross|IsActive=T|SuppressAll=T
|RECORD=22|IndexInSheet=177|OwnerPartId=-1|Location.X=1280|Location.Y=268|Color=255|Orientation=1|Symbol=Thin Cross|IsActive=T|SuppressAll=T
|RECORD=22|IndexInSheet=178|OwnerPartId=-1|Location.X=1160|Location.Y=298|Color=255|Orientation=1|Symbol=Thin Cross|IsActive=T|SuppressAll=T
|RECORD=22|IndexInSheet=179|OwnerPartId=-1|Location.X=1160|Location.Y=288|Color=255|Orientation=1|Symbol=Thin Cross|IsActive=T|SuppressAll=T
|RECORD=22|IndexInSheet=180|OwnerPartId=-1|Location.X=1160|Location.Y=278|Color=255|Orientation=1|Symbol=Thin Cross|IsActive=T|SuppressAll=T
|RECORD=22|IndexInSheet=181|OwnerPartId=-1|Location.X=1160|Location.Y=268|Color=255|Orientation=1|Symbol=Thin Cross|IsActive=T|SuppressAll=T
|RECORD=22|IndexInSheet=182|OwnerPartId=-1|Location.X=1160|Location.Y=248|Color=255|Orientation=1|Symbol=Thin Cross|IsActive=T|SuppressAll=T
|RECORD=22|IndexInSheet=183|OwnerPartId=-1|Location.X=1160|Location.Y=238|Color=255|Orientation=1|Symbol=Thin Cross|IsActive=T|SuppressAll=T
|RECORD=22|IndexInSheet=184|OwnerPartId=-1|Location.X=1160|Location.Y=228|Color=255|Orientation=1|Symbol=Thin Cross|IsActive=T|SuppressAll=T
|RECORD=22|IndexInSheet=185|OwnerPartId=-1|Location.X=1160|Location.Y=218|Color=255|Orientation=1|Symbol=Thin Cross|IsActive=T|SuppressAll=T
|RECORD=22|IndexInSheet=186|OwnerPartId=-1|Location.X=1280|Location.Y=218|Color=255|Orientation=1|Symbol=Thin Cross|IsActive=T|SuppressAll=T
|RECORD=22|IndexInSheet=187|OwnerPartId=-1|Location.X=1280|Location.Y=228|Color=255|Orientation=1|Symbol=Thin Cross|IsActive=T|SuppressAll=T
|RECORD=22|IndexInSheet=188|OwnerPartId=-1|Location.X=1280|Location.Y=238|Color=255|Orientation=1|Symbol=Thin Cross|IsActive=T|SuppressAll=T
|RECORD=22|IndexInSheet=189|OwnerPartId=-1|Location.X=1280|Location.Y=248|Color=255|Orientation=1|Symbol=Thin Cross|IsActive=T|SuppressAll=T
|RECORD=22|IndexInSheet=190|OwnerPartId=-1|Location.X=1280|Location.Y=198|Color=255|Orientation=1|Symbol=Thin Cross|IsActive=T|SuppressAll=T
|RECORD=22|IndexInSheet=191|OwnerPartId=-1|Location.X=1280|Location.Y=188|Color=255|Orientation=1|Symbol=Thin Cross|IsActive=T|SuppressAll=T
|RECORD=22|IndexInSheet=192|OwnerPartId=-1|Location.X=1280|Location.Y=178|Color=255|Orientation=1|Symbol=Thin Cross|IsActive=T|SuppressAll=T
|RECORD=22|IndexInSheet=193|OwnerPartId=-1|Location.X=1280|Location.Y=168|Color=255|Orientation=1|Symbol=Thin Cross|IsActive=T|SuppressAll=T
|RECORD=22|IndexInSheet=194|OwnerPartId=-1|Location.X=1160|Location.Y=198|Color=255|Orientation=1|Symbol=Thin Cross|IsActive=T|SuppressAll=T
|RECORD=22|IndexInSheet=195|OwnerPartId=-1|Location.X=1160|Location.Y=188|Color=255|Orientation=1|Symbol=Thin Cross|IsActive=T|SuppressAll=T
|RECORD=22|IndexInSheet=196|OwnerPartId=-1|Location.X=1160|Location.Y=178|Color=255|Orientation=1|Symbol=Thin Cross|IsActive=T|SuppressAll=T
|RECORD=22|IndexInSheet=197|OwnerPartId=-1|Location.X=1160|Location.Y=168|Color=255|Orientation=1|Symbol=Thin Cross|IsActive=T|SuppressAll=T
|RECORD=22|IndexInSheet=198|OwnerPartId=-1|Location.X=1160|Location.Y=148|Color=255|Orientation=1|Symbol=Thin Cross|IsActive=T|SuppressAll=T
|RECORD=22|IndexInSheet=199|OwnerPartId=-1|Location.X=1160|Location.Y=138|Color=255|Orientation=1|Symbol=Thin Cross|IsActive=T|SuppressAll=T
|RECORD=22|IndexInSheet=200|OwnerPartId=-1|Location.X=1160|Location.Y=118|Color=255|Orientation=1|Symbol=Thin Cross|IsActive=T|SuppressAll=T
|RECORD=22|IndexInSheet=201|OwnerPartId=-1|Location.X=1160|Location.Y=128|Color=255|Orientation=1|Symbol=Thin Cross|IsActive=T|SuppressAll=T
|RECORD=22|IndexInSheet=202|OwnerPartId=-1|Location.X=1160|Location.Y=98|Color=255|Orientation=1|Symbol=Thin Cross|IsActive=T|SuppressAll=T
|RECORD=22|IndexInSheet=203|OwnerPartId=-1|Location.X=1160|Location.Y=88|Color=255|Orientation=1|Symbol=Thin Cross|IsActive=T|SuppressAll=T
|RECORD=22|IndexInSheet=204|OwnerPartId=-1|Location.X=1280|Location.Y=88|Color=255|Orientation=1|Symbol=Thin Cross|IsActive=T|SuppressAll=T
|RECORD=22|IndexInSheet=205|OwnerPartId=-1|Location.X=1280|Location.Y=98|Color=255|Orientation=1|Symbol=Thin Cross|IsActive=T|SuppressAll=T
|RECORD=22|IndexInSheet=206|OwnerPartId=-1|Location.X=1280|Location.Y=118|Color=255|Orientation=1|Symbol=Thin Cross|IsActive=T|SuppressAll=T
|RECORD=22|IndexInSheet=207|OwnerPartId=-1|Location.X=1280|Location.Y=128|Color=255|Orientation=1|Symbol=Thin Cross|IsActive=T|SuppressAll=T
|RECORD=22|IndexInSheet=208|OwnerPartId=-1|Location.X=1280|Location.Y=138|Color=255|Orientation=1|Symbol=Thin Cross|IsActive=T|SuppressAll=T
|RECORD=22|IndexInSheet=209|OwnerPartId=-1|Location.X=1280|Location.Y=148|Color=255|Orientation=1|Symbol=Thin Cross|IsActive=T|SuppressAll=T
|RECORD=22|IndexInSheet=210|OwnerPartId=-1|Location.X=460|Location.Y=488|Color=255|Orientation=1|Symbol=Thin Cross|IsActive=T|SuppressAll=T
|RECORD=22|IndexInSheet=211|OwnerPartId=-1|Location.X=580|Location.Y=488|Color=255|Orientation=1|Symbol=Thin Cross|IsActive=T|SuppressAll=T
|RECORD=22|IndexInSheet=212|OwnerPartId=-1|Location.X=580|Location.Y=478|Color=255|Orientation=1|Symbol=Thin Cross|IsActive=T|SuppressAll=T
|RECORD=22|IndexInSheet=213|OwnerPartId=-1|Location.X=580|Location.Y=468|Color=255|Orientation=1|Symbol=Thin Cross|IsActive=T|SuppressAll=T
|RECORD=22|IndexInSheet=214|OwnerPartId=-1|Location.X=460|Location.Y=438|Color=255|Orientation=1|Symbol=Thin Cross|IsActive=T|SuppressAll=T
|RECORD=22|IndexInSheet=215|OwnerPartId=-1|Location.X=460|Location.Y=428|Color=255|Orientation=1|Symbol=Thin Cross|IsActive=T|SuppressAll=T
|RECORD=22|IndexInSheet=216|OwnerPartId=-1|Location.X=460|Location.Y=418|Color=255|Orientation=1|Symbol=Thin Cross|IsActive=T|SuppressAll=T
|RECORD=22|IndexInSheet=217|OwnerPartId=-1|Location.X=460|Location.Y=378|Color=255|Orientation=1|Symbol=Thin Cross|IsActive=T|SuppressAll=T
|RECORD=22|IndexInSheet=218|OwnerPartId=-1|Location.X=460|Location.Y=368|Color=255|Orientation=1|Symbol=Thin Cross|IsActive=T|SuppressAll=T
|RECORD=22|IndexInSheet=219|OwnerPartId=-1|Location.X=460|Location.Y=238|Color=255|Orientation=1|Symbol=Thin Cross|IsActive=T|SuppressAll=T
|RECORD=22|IndexInSheet=220|OwnerPartId=-1|Location.X=460|Location.Y=228|Color=255|Orientation=1|Symbol=Thin Cross|IsActive=T|SuppressAll=T
|RECORD=22|IndexInSheet=221|OwnerPartId=-1|Location.X=460|Location.Y=218|Color=255|Orientation=1|Symbol=Thin Cross|IsActive=T|SuppressAll=T
|RECORD=22|IndexInSheet=222|OwnerPartId=-1|Location.X=580|Location.Y=248|Color=255|Orientation=1|Symbol=Thin Cross|IsActive=T|SuppressAll=T
|RECORD=22|IndexInSheet=223|OwnerPartId=-1|Location.X=580|Location.Y=238|Color=255|Orientation=1|Symbol=Thin Cross|IsActive=T|SuppressAll=T
|RECORD=22|IndexInSheet=224|OwnerPartId=-1|Location.X=580|Location.Y=228|Color=255|Orientation=1|Symbol=Thin Cross|IsActive=T|SuppressAll=T
|RECORD=22|IndexInSheet=225|OwnerPartId=-1|Location.X=580|Location.Y=218|Color=255|Orientation=1|Symbol=Thin Cross|IsActive=T|SuppressAll=T
|RECORD=22|IndexInSheet=226|OwnerPartId=-1|Location.X=460|Location.Y=198|Color=255|Orientation=1|Symbol=Thin Cross|IsActive=T|SuppressAll=T
|RECORD=22|IndexInSheet=227|OwnerPartId=-1|Location.X=460|Location.Y=188|Color=255|Orientation=1|Symbol=Thin Cross|IsActive=T|SuppressAll=T
|RECORD=22|IndexInSheet=228|OwnerPartId=-1|Location.X=460|Location.Y=178|Color=255|Orientation=1|Symbol=Thin Cross|IsActive=T|SuppressAll=T
|RECORD=22|IndexInSheet=229|OwnerPartId=-1|Location.X=460|Location.Y=168|Color=255|Orientation=1|Symbol=Thin Cross|IsActive=T|SuppressAll=T
|RECORD=22|IndexInSheet=230|OwnerPartId=-1|Location.X=580|Location.Y=198|Color=255|Orientation=1|Symbol=Thin Cross|IsActive=T|SuppressAll=T
|RECORD=22|IndexInSheet=231|OwnerPartId=-1|Location.X=580|Location.Y=188|Color=255|Orientation=1|Symbol=Thin Cross|IsActive=T|SuppressAll=T
|RECORD=22|IndexInSheet=232|OwnerPartId=-1|Location.X=580|Location.Y=178|Color=255|Orientation=1|Symbol=Thin Cross|IsActive=T|SuppressAll=T
|RECORD=22|IndexInSheet=233|OwnerPartId=-1|Location.X=580|Location.Y=168|Color=255|Orientation=1|Symbol=Thin Cross|IsActive=T|SuppressAll=T
|RECORD=22|IndexInSheet=234|OwnerPartId=-1|Location.X=580|Location.Y=148|Color=255|Orientation=1|Symbol=Thin Cross|IsActive=T|SuppressAll=T
|RECORD=22|IndexInSheet=235|OwnerPartId=-1|Location.X=580|Location.Y=138|Color=255|Orientation=1|Symbol=Thin Cross|IsActive=T|SuppressAll=T
|RECORD=22|IndexInSheet=236|OwnerPartId=-1|Location.X=460|Location.Y=148|Color=255|Orientation=1|Symbol=Thin Cross|IsActive=T|SuppressAll=T
|RECORD=22|IndexInSheet=237|OwnerPartId=-1|Location.X=460|Location.Y=148|Color=255|Orientation=1|Symbol=Thin Cross|IsActive=T|SuppressAll=T
|RECORD=22|IndexInSheet=238|OwnerPartId=-1|Location.X=460|Location.Y=138|Color=255|Orientation=1|Symbol=Thin Cross|IsActive=T|SuppressAll=T
|RECORD=22|IndexInSheet=239|OwnerPartId=-1|Location.X=460|Location.Y=98|Color=255|Orientation=1|Symbol=Thin Cross|IsActive=T|SuppressAll=T
|RECORD=22|IndexInSheet=240|OwnerPartId=-1|Location.X=460|Location.Y=88|Color=255|Orientation=1|Symbol=Thin Cross|IsActive=T|SuppressAll=T
|RECORD=22|IndexInSheet=241|OwnerPartId=-1|Location.X=580|Location.Y=88|Color=255|Orientation=1|Symbol=Thin Cross|IsActive=T|SuppressAll=T
|RECORD=22|IndexInSheet=242|OwnerPartId=-1|Location.X=580|Location.Y=98|Color=255|Orientation=1|Symbol=Thin Cross|IsActive=T|SuppressAll=T
|RECORD=41|IndexInSheet=243|OwnerPartId=-1|Color=8388608|FontID=1|IsHidden=T|Name=ConfigurationParameters|ReadOnlyState=1
|RECORD=41|IndexInSheet=244|OwnerPartId=-1|Color=8388608|FontID=1|IsHidden=T|Name=ConfiguratorName|ReadOnlyState=1
|RECORD=41|IndexInSheet=245|OwnerPartId=-1|Color=8388608|FontID=1|IsHidden=T|Name=VersionControl_RevNumber|ReadOnlyState=1
|RECORD=41|IndexInSheet=246|OwnerPartId=-1|Color=8388608|FontID=1|IsHidden=T|Name=IsUserConfigurable|ReadOnlyState=1
|RECORD=41|IndexInSheet=247|OwnerPartId=-1|Color=8388608|FontID=1|IsHidden=T|Name=VersionControl_ProjFolderRevNumber|ReadOnlyState=1
|RECORD=41|IndexInSheet=248|OwnerPartId=-1|Color=8388608|FontID=1|IsHidden=T|Name=SPICEModelCache|ReadOnlyState=1
|RECORD=22|IndexInSheet=249|OwnerPartId=-1|Location.X=1290|Location.Y=968|Color=255|Orientation=1|Symbol=Thin Cross|IsActive=T|SuppressAll=T
|RECORD=22|IndexInSheet=250|OwnerPartId=-1|Location.X=1170|Location.Y=788|Color=255|Orientation=1|Symbol=Thin Cross|IsActive=T|SuppressAll=T
|RECORD=22|IndexInSheet=251|OwnerPartId=-1|Location.X=1170|Location.Y=768|Color=255|Orientation=1|Symbol=Thin Cross|IsActive=T|SuppressAll=T
|RECORD=22|IndexInSheet=252|OwnerPartId=-1|Location.X=1170|Location.Y=738|Color=255|Orientation=1|Symbol=Thin Cross|IsActive=T|SuppressAll=T
|RECORD=17|IndexInSheet=253|OwnerPartId=-1|ShowNetName=T|Location.X=1061|Location.Y=638|Orientation=2|Color=255|FontID=1|Text=UART1_TXD|IsCrossSheetConnector=T
|RECORD=17|IndexInSheet=254|OwnerPartId=-1|ShowNetName=T|Location.X=1060|Location.Y=608|Orientation=2|Color=255|FontID=1|Text=UART1_RXD|IsCrossSheetConnector=T
|RECORD=17|IndexInSheet=255|OwnerPartId=-1|ShowNetName=T|Location.X=690|Location.Y=448|Color=255|FontID=1|Text=IO_LED1|IsCrossSheetConnector=T
|RECORD=17|IndexInSheet=256|OwnerPartId=-1|ShowNetName=T|Location.X=690|Location.Y=438|Color=255|FontID=1|Text=IO_LED2|IsCrossSheetConnector=T
|RECORD=17|IndexInSheet=257|OwnerPartId=-1|ShowNetName=T|Location.X=690|Location.Y=428|Color=255|FontID=1|Text=IO_LED3|IsCrossSheetConnector=T
|RECORD=17|IndexInSheet=258|OwnerPartId=-1|ShowNetName=T|Location.X=691|Location.Y=418|Color=255|FontID=1|Text=IO_LED4|IsCrossSheetConnector=T
|RECORD=17|IndexInSheet=259|OwnerPartId=-1|ShowNetName=T|Location.X=690|Location.Y=498|Color=255|FontID=1|Text=GPS2_RX|IsCrossSheetConnector=T
|RECORD=17|IndexInSheet=260|OwnerPartId=-1|ShowNetName=T|Location.X=318|Location.Y=498|Orientation=2|Color=255|FontID=1|Text=GPS2_TX|IsCrossSheetConnector=T
|RECORD=17|IndexInSheet=261|OwnerPartId=-1|ShowNetName=T|Location.X=319|Location.Y=468|Orientation=2|Color=255|FontID=1|Text=GPS2_TP2|IsCrossSheetConnector=T
|RECORD=17|IndexInSheet=262|OwnerPartId=-1|ShowNetName=T|Location.X=319|Location.Y=478|Orientation=2|Color=255|FontID=1|Text=GPS2_TP1|IsCrossSheetConnector=T
|RECORD=17|IndexInSheet=263|OwnerPartId=-1|ShowNetName=T|Location.X=319|Location.Y=448|Orientation=2|Color=255|FontID=1|Text=GPS2_RST|IsCrossSheetConnector=T
|RECORD=22|IndexInSheet=264|OwnerPartId=-1|Location.X=460|Location.Y=888|Color=255|Orientation=1|Symbol=Thin Cross|IsActive=T|SuppressAll=T
|RECORD=22|IndexInSheet=265|OwnerPartId=-1|Location.X=460|Location.Y=878|Color=255|Orientation=1|Symbol=Thin Cross|IsActive=T|SuppressAll=T
|RECORD=22|IndexInSheet=266|OwnerPartId=-1|Location.X=460|Location.Y=868|Color=255|Orientation=1|Symbol=Thin Cross|IsActive=T|SuppressAll=T
|RECORD=22|IndexInSheet=267|OwnerPartId=-1|Location.X=460|Location.Y=858|Color=255|Orientation=1|Symbol=Thin Cross|IsActive=T|SuppressAll=T
|RECORD=22|IndexInSheet=268|OwnerPartId=-1|Location.X=460|Location.Y=818|Color=255|Orientation=1|Symbol=Thin Cross|IsActive=T|SuppressAll=T
|RECORD=22|IndexInSheet=269|OwnerPartId=-1|Location.X=460|Location.Y=778|Color=255|Orientation=1|Symbol=Thin Cross|IsActive=T|SuppressAll=T
|RECORD=22|IndexInSheet=270|OwnerPartId=-1|Location.X=460|Location.Y=768|Color=255|Orientation=1|Symbol=Thin Cross|IsActive=T|SuppressAll=T
|RECORD=22|IndexInSheet=271|OwnerPartId=-1|Location.X=1170|Location.Y=838|Color=255|Orientation=1|Symbol=Thin Cross|IsActive=T|SuppressAll=T
|RECORD=17|IndexInSheet=272|OwnerPartId=-1|ShowNetName=T|Location.X=320|Location.Y=348|Orientation=2|Color=255|FontID=1|Text=ANT1_IO_OUT|IsCrossSheetConnector=T
|RECORD=17|IndexInSheet=273|OwnerPartId=-1|ShowNetName=T|Location.X=320|Location.Y=338|Orientation=2|Color=255|FontID=1|Text=ANT1_IO_IN|IsCrossSheetConnector=T
|RECORD=17|IndexInSheet=274|OwnerPartId=-1|ShowNetName=T|Location.X=320|Location.Y=328|Orientation=2|Color=255|FontID=1|Text=ANT2_IO_OUT|IsCrossSheetConnector=T
|RECORD=17|IndexInSheet=275|OwnerPartId=-1|ShowNetName=T|Location.X=320|Location.Y=318|Orientation=2|Color=255|FontID=1|Text=ANT2_IO_IN|IsCrossSheetConnector=T
|RECORD=17|IndexInSheet=276|OwnerPartId=-1|ShowNetName=T|Location.X=320|Location.Y=298|Orientation=2|Color=255|FontID=1|Text=ANT3_IO_OUT|IsCrossSheetConnector=T
|RECORD=17|IndexInSheet=277|OwnerPartId=-1|ShowNetName=T|Location.X=320|Location.Y=288|Orientation=2|Color=255|FontID=1|Text=ANT3_IO_IN|IsCrossSheetConnector=T
|RECORD=17|IndexInSheet=278|OwnerPartId=-1|ShowNetName=T|Location.X=320|Location.Y=278|Orientation=2|Color=255|FontID=1|Text=ANT4_IO_OUT|IsCrossSheetConnector=T
|RECORD=17|IndexInSheet=279|OwnerPartId=-1|ShowNetName=T|Location.X=320|Location.Y=268|Orientation=2|Color=255|FontID=1|Text=ANT4_IO_IN|IsCrossSheetConnector=T
|RECORD=17|IndexInSheet=280|OwnerPartId=-1|ShowNetName=T|Location.X=691|Location.Y=348|Color=255|FontID=1|Text=EXT_GPIO_7|IsCrossSheetConnector=T
|RECORD=17|IndexInSheet=281|OwnerPartId=-1|ShowNetName=T|Location.X=691|Location.Y=338|Color=255|FontID=1|Text=EXT_GPIO_8|IsCrossSheetConnector=T
|RECORD=17|IndexInSheet=282|OwnerPartId=-1|ShowNetName=T|Location.X=691|Location.Y=328|Color=255|FontID=1|Text=EXT_GPIO_9|IsCrossSheetConnector=T
|RECORD=17|IndexInSheet=283|OwnerPartId=-1|ShowNetName=T|Location.X=691|Location.Y=318|Color=255|FontID=1|Text=EXT_GPIO_10|IsCrossSheetConnector=T
|RECORD=41|IndexInSheet=284|OwnerPartId=-1|Color=8388608|FontID=1|IsHidden=T|Text=*|Name=CurrentTime|ReadOnlyState=1
|RECORD=41|IndexInSheet=285|OwnerPartId=-1|Color=8388608|FontID=1|IsHidden=T|Text=*|Name=CurrentDate|ReadOnlyState=1
|RECORD=41|IndexInSheet=286|OwnerPartId=-1|Color=8388608|FontID=1|IsHidden=T|Text=*|Name=Time|ReadOnlyState=1
|RECORD=41|IndexInSheet=287|OwnerPartId=-1|Color=8388608|FontID=1|IsHidden=T|Text=*|Name=Date|ReadOnlyState=1
|RECORD=41|IndexInSheet=288|OwnerPartId=-1|Color=8388608|FontID=1|IsHidden=T|Text=*|Name=DocumentFullPathAndName|ReadOnlyState=1
|RECORD=41|IndexInSheet=289|OwnerPartId=-1|Color=8388608|FontID=1|IsHidden=T|Text=*|Name=DocumentName|ReadOnlyState=1
|RECORD=41|IndexInSheet=290|OwnerPartId=-1|Color=8388608|FontID=1|IsHidden=T|Text=*|Name=ModifiedDate|ReadOnlyState=1
|RECORD=41|IndexInSheet=291|OwnerPartId=-1|Color=8388608|FontID=1|IsHidden=T|Text=*|Name=ApprovedBy|ReadOnlyState=1
|RECORD=41|IndexInSheet=292|OwnerPartId=-1|Color=8388608|FontID=1|IsHidden=T|Text=*|Name=CheckedBy|ReadOnlyState=1
|RECORD=41|IndexInSheet=293|OwnerPartId=-1|Color=8388608|FontID=1|IsHidden=T|Text=*|Name=Author|ReadOnlyState=1
|RECORD=41|IndexInSheet=294|OwnerPartId=-1|Color=8388608|FontID=1|IsHidden=T|Text=*|Name=CompanyName|ReadOnlyState=1
|RECORD=41|IndexInSheet=295|OwnerPartId=-1|Color=8388608|FontID=1|IsHidden=T|Text=*|Name=DrawnBy|ReadOnlyState=1
|RECORD=41|IndexInSheet=296|OwnerPartId=-1|Color=8388608|FontID=1|IsHidden=T|Text=*|Name=Engineer|ReadOnlyState=1
|RECORD=41|IndexInSheet=297|OwnerPartId=-1|Color=8388608|FontID=1|IsHidden=T|Text=*|Name=Organization|ReadOnlyState=1
|RECORD=41|IndexInSheet=298|OwnerPartId=-1|Color=8388608|FontID=1|IsHidden=T|Text=*|Name=Address1|ReadOnlyState=1
|RECORD=41|IndexInSheet=299|OwnerPartId=-1|Color=8388608|FontID=1|IsHidden=T|Text=*|Name=Address2|ReadOnlyState=1
|RECORD=41|IndexInSheet=300|OwnerPartId=-1|Color=8388608|FontID=1|IsHidden=T|Text=*|Name=Address3|ReadOnlyState=1
|RECORD=41|IndexInSheet=301|OwnerPartId=-1|Color=8388608|FontID=1|IsHidden=T|Text=*|Name=Address4|ReadOnlyState=1
|RECORD=41|IndexInSheet=302|OwnerPartId=-1|Color=8388608|FontID=1|IsHidden=T|Text=*|Name=Title|ReadOnlyState=1
|RECORD=41|IndexInSheet=303|OwnerPartId=-1|Color=8388608|FontID=1|IsHidden=T|Text=*|Name=DocumentNumber|ReadOnlyState=1
|RECORD=41|IndexInSheet=304|OwnerPartId=-1|Color=8388608|FontID=1|IsHidden=T|Text=*|Name=Revision|ReadOnlyState=1
|RECORD=41|IndexInSheet=305|OwnerPartId=-1|Color=8388608|FontID=1|IsHidden=T|Text=*|Name=SheetNumber|ReadOnlyState=1
|RECORD=41|IndexInSheet=306|OwnerPartId=-1|Color=8388608|FontID=1|IsHidden=T|Text=*|Name=SheetTotal|ReadOnlyState=1
|RECORD=41|IndexInSheet=307|OwnerPartId=-1|Color=8388608|FontID=1|IsHidden=T|Text=*|Name=Rule|ReadOnlyState=1
|RECORD=41|IndexInSheet=308|OwnerPartId=-1|Color=8388608|FontID=1|IsHidden=T|Text=*|Name=ImagePath|ReadOnlyState=1
|RECORD=41|IndexInSheet=309|OwnerPartId=-1|Color=8388608|FontID=1|IsHidden=T|Text=*|Name=ProjectName|ReadOnlyState=1
|RECORD=41|IndexInSheet=310|OwnerPartId=-1|Color=8388608|FontID=1|IsHidden=T|Text=*|Name=Application_BuildNumber|ReadOnlyState=1
|RECORD=22|IndexInSheet=311|OwnerPartId=-1|Location.X=580|Location.Y=768|Color=255|Orientation=1|Symbol=Thin Cross|IsActive=T|SuppressAll=T
|RECORD=22|IndexInSheet=312|OwnerPartId=-1|Location.X=580|Location.Y=758|Color=255|Orientation=1|Symbol=Thin Cross|IsActive=T|SuppressAll=T
|RECORD=22|IndexInSheet=313|OwnerPartId=-1|Location.X=580|Location.Y=728|Color=255|Orientation=1|Symbol=Thin Cross|IsActive=T|SuppressAll=T
|RECORD=22|IndexInSheet=314|OwnerPartId=-1|Location.X=580|Location.Y=718|Color=255|Orientation=1|Symbol=Thin Cross|IsActive=T|SuppressAll=T
|RECORD=22|IndexInSheet=315|OwnerPartId=-1|Location.X=580|Location.Y=688|Color=255|Orientation=1|Symbol=Thin Cross|IsActive=T|SuppressAll=T
|RECORD=22|IndexInSheet=316|OwnerPartId=-1|Location.X=580|Location.Y=678|Color=255|Orientation=1|Symbol=Thin Cross|IsActive=T|SuppressAll=T
|RECORD=22|IndexInSheet=317|OwnerPartId=-1|Location.X=1290|Location.Y=678|Color=255|Orientation=1|Symbol=Thin Cross|IsActive=T|SuppressAll=T
|RECORD=22|IndexInSheet=318|OwnerPartId=-1|Location.X=1290|Location.Y=828|Color=255|Orientation=1|Symbol=Thin Cross|IsActive=T|SuppressAll=T
|RECORD=22|IndexInSheet=319|OwnerPartId=-1|Location.X=460|Location.Y=248|Color=255|Orientation=1|Symbol=Thin Cross|IsActive=T|SuppressAll=T
|RECORD=17|IndexInSheet=320|OwnerPartId=-1|ShowNetName=T|Location.X=691|Location.Y=298|Color=255|FontID=1|Text=EXT_GPIO_1|IsCrossSheetConnector=T
|RECORD=17|IndexInSheet=321|OwnerPartId=-1|ShowNetName=T|Location.X=691|Location.Y=288|Color=255|FontID=1|Text=EXT_GPIO_2|IsCrossSheetConnector=T
|RECORD=17|IndexInSheet=322|OwnerPartId=-1|ShowNetName=T|Location.X=691|Location.Y=278|Color=255|FontID=1|Text=EXT_GPIO_3|IsCrossSheetConnector=T
|RECORD=17|IndexInSheet=323|OwnerPartId=-1|ShowNetName=T|Location.X=691|Location.Y=268|Color=255|FontID=1|Text=EXT_GPIO_4|IsCrossSheetConnector=T
|RECORD=17|IndexInSheet=324|OwnerPartId=-1|ShowNetName=T|Location.X=1059|Location.Y=918|Orientation=2|Color=255|FontID=1|Text=ANT1_OUT|IsCrossSheetConnector=T
|RECORD=17|IndexInSheet=325|OwnerPartId=-1|ShowNetName=T|Location.X=1059|Location.Y=888|Orientation=2|Color=255|FontID=1|Text=ANT1_IN|IsCrossSheetConnector=T
|RECORD=17|IndexInSheet=326|OwnerPartId=-1|ShowNetName=T|Location.X=1059|Location.Y=908|Orientation=2|Color=255|FontID=1|Text=ANT2_OUT|IsCrossSheetConnector=T
|RECORD=17|IndexInSheet=327|OwnerPartId=-1|ShowNetName=T|Location.X=1059|Location.Y=878|Orientation=2|Color=255|FontID=1|Text=ANT2_IN|IsCrossSheetConnector=T
|RECORD=17|IndexInSheet=328|OwnerPartId=-1|ShowNetName=T|Location.X=1059|Location.Y=868|Orientation=2|Color=255|FontID=1|Text=ANT3_OUT|IsCrossSheetConnector=T
|RECORD=17|IndexInSheet=329|OwnerPartId=-1|ShowNetName=T|Location.X=1352|Location.Y=918|Color=255|FontID=1|Text=ANT3_IN|IsCrossSheetConnector=T
|RECORD=17|IndexInSheet=330|OwnerPartId=-1|ShowNetName=T|Location.X=1059|Location.Y=858|Orientation=2|Color=255|FontID=1|Text=ANT4_OUT|IsCrossSheetConnector=T
|RECORD=17|IndexInSheet=331|OwnerPartId=-1|ShowNetName=T|Location.X=1352|Location.Y=908|Color=255|FontID=1|Text=ANT4_IN|IsCrossSheetConnector=T
|RECORD=17|IndexInSheet=332|OwnerPartId=-1|ShowNetName=T|Location.X=691|Location.Y=778|Color=255|FontID=1|Text=EXT_EEPROM_WP|IsCrossSheetConnector=T
|RECORD=1|LibReference=Single FPGA Conn|PartCount=2|DisplayModeCount=1|IndexInSheet=333|OwnerPartId=-1|Location.X=460|Location.Y=578|CurrentPartId=1|LibraryPath=*|SourceLibraryName=FPGA_CONN.SchLib|TargetFileName=*|AreaColor=11599871|Color=128|PartIDLocked=T|PinsMoveable=T|DesignItemId=Single FPGA Conn|AllPinCount=84
|RECORD=41|OwnerIndex=367|OwnerPartId=-1|Location.X=455|Location.Y=998|Color=8388608|FontID=1|IsHidden=T|Text=Digi-Key|Name=Supplier 1|ReadOnlyState=3
|RECORD=41|OwnerIndex=367|IndexInSheet=1|OwnerPartId=-1|Location.X=490|Location.Y=998|Color=8388608|FontID=1|IsHidden=T|Text=255-3246-1-ND|Name=Supplier Part Number 1|ReadOnlyState=3
|RECORD=41|OwnerIndex=367|IndexInSheet=2|OwnerPartId=-1|Location.X=490|Location.Y=548|Color=8388608|FontID=1|Text=AXK680347YG|Name=Part Number
|RECORD=14|OwnerIndex=367|IsNotAccesible=T|IndexInSheet=3|OwnerPartId=1|Location.X=490|Location.Y=568|Corner.X=550|Corner.Y=998|Color=128|AreaColor=11599871|IsSolid=T
|RECORD=2|OwnerIndex=367|OwnerPartId=1|FormalType=1|PinConglomerate=26|PinLength=30|Location.X=490|Location.Y=988|Name=1|Designator=1|PinPropagationDelay=0.000000E+000
|RECORD=2|OwnerIndex=367|OwnerPartId=1|FormalType=1|PinConglomerate=24|PinLength=30|Location.X=550|Location.Y=988|Name=2|Designator=2|PinPropagationDelay=0.000000E+000
|RECORD=2|OwnerIndex=367|OwnerPartId=1|FormalType=1|PinConglomerate=26|PinLength=30|Location.X=490|Location.Y=978|Name=3|Designator=3|PinPropagationDelay=0.000000E+000
|RECORD=2|OwnerIndex=367|OwnerPartId=1|FormalType=1|PinConglomerate=24|PinLength=30|Location.X=550|Location.Y=978|Name=4|Designator=4|PinPropagationDelay=0.000000E+000
|RECORD=2|OwnerIndex=367|OwnerPartId=1|FormalType=1|PinConglomerate=26|PinLength=30|Location.X=490|Location.Y=968|Name=5|Designator=5|PinPropagationDelay=0.000000E+000
|RECORD=2|OwnerIndex=367|OwnerPartId=1|FormalType=1|PinConglomerate=24|PinLength=30|Location.X=550|Location.Y=968|Name=6|Designator=6|PinPropagationDelay=0.000000E+000
|RECORD=2|OwnerIndex=367|OwnerPartId=1|FormalType=1|PinConglomerate=26|PinLength=30|Location.X=490|Location.Y=958|Name=7|Designator=7|PinPropagationDelay=0.000000E+000
|RECORD=2|OwnerIndex=367|OwnerPartId=1|FormalType=1|PinConglomerate=24|PinLength=30|Location.X=550|Location.Y=958|Name=8|Designator=8|PinPropagationDelay=0.000000E+000
|RECORD=2|OwnerIndex=367|OwnerPartId=1|FormalType=1|PinConglomerate=26|PinLength=30|Location.X=490|Location.Y=948|Name=9|Designator=9|PinPropagationDelay=0.000000E+000
|RECORD=2|OwnerIndex=367|OwnerPartId=1|FormalType=1|PinConglomerate=24|PinLength=30|Location.X=550|Location.Y=948|Name=10|Designator=10|PinPropagationDelay=0.000000E+000
|RECORD=2|OwnerIndex=367|OwnerPartId=1|FormalType=1|PinConglomerate=26|PinLength=30|Location.X=490|Location.Y=938|Name=11|Designator=11|PinPropagationDelay=0.000000E+000
|RECORD=2|OwnerIndex=367|OwnerPartId=1|FormalType=1|PinConglomerate=24|PinLength=30|Location.X=550|Location.Y=938|Name=12|Designator=12|PinPropagationDelay=0.000000E+000
|RECORD=2|OwnerIndex=367|OwnerPartId=1|FormalType=1|PinConglomerate=26|PinLength=30|Location.X=490|Location.Y=928|Name=13|Designator=13|PinPropagationDelay=0.000000E+000
|RECORD=2|OwnerIndex=367|OwnerPartId=1|FormalType=1|PinConglomerate=24|PinLength=30|Location.X=550|Location.Y=928|Name=14|Designator=14|PinPropagationDelay=0.000000E+000
|RECORD=2|OwnerIndex=367|OwnerPartId=1|FormalType=1|PinConglomerate=26|PinLength=30|Location.X=490|Location.Y=918|Name=15|Designator=15|PinPropagationDelay=0.000000E+000
|RECORD=2|OwnerIndex=367|OwnerPartId=1|FormalType=1|PinConglomerate=24|PinLength=30|Location.X=550|Location.Y=918|Name=16|Designator=16|PinPropagationDelay=0.000000E+000
|RECORD=2|OwnerIndex=367|OwnerPartId=1|FormalType=1|PinConglomerate=26|PinLength=30|Location.X=490|Location.Y=908|Name=17|Designator=17|PinPropagationDelay=0.000000E+000
|RECORD=2|OwnerIndex=367|OwnerPartId=1|FormalType=1|PinConglomerate=24|PinLength=30|Location.X=550|Location.Y=908|Name=18|Designator=18|PinPropagationDelay=0.000000E+000
|RECORD=2|OwnerIndex=367|OwnerPartId=1|FormalType=1|PinConglomerate=26|PinLength=30|Location.X=490|Location.Y=898|Name=19|Designator=19|PinPropagationDelay=0.000000E+000
|RECORD=2|OwnerIndex=367|OwnerPartId=1|FormalType=1|PinConglomerate=24|PinLength=30|Location.X=550|Location.Y=898|Name=20|Designator=20|PinPropagationDelay=0.000000E+000
|RECORD=2|OwnerIndex=367|OwnerPartId=1|FormalType=1|PinConglomerate=26|PinLength=30|Location.X=490|Location.Y=888|Name=21|Designator=21|PinPropagationDelay=0.000000E+000
|RECORD=2|OwnerIndex=367|OwnerPartId=1|FormalType=1|PinConglomerate=24|PinLength=30|Location.X=550|Location.Y=888|Name=22|Designator=22|PinPropagationDelay=0.000000E+000
|RECORD=2|OwnerIndex=367|OwnerPartId=1|FormalType=1|PinConglomerate=26|PinLength=30|Location.X=490|Location.Y=878|Name=23|Designator=23|PinPropagationDelay=0.000000E+000
|RECORD=2|OwnerIndex=367|OwnerPartId=1|FormalType=1|PinConglomerate=24|PinLength=30|Location.X=550|Location.Y=878|Name=24|Designator=24|PinPropagationDelay=0.000000E+000
|RECORD=2|OwnerIndex=367|OwnerPartId=1|FormalType=1|PinConglomerate=26|PinLength=30|Location.X=490|Location.Y=868|Name=25|Designator=25|PinPropagationDelay=0.000000E+000
|RECORD=2|OwnerIndex=367|OwnerPartId=1|FormalType=1|PinConglomerate=24|PinLength=30|Location.X=550|Location.Y=868|Name=26|Designator=26|PinPropagationDelay=0.000000E+000
|RECORD=2|OwnerIndex=367|OwnerPartId=1|FormalType=1|PinConglomerate=26|PinLength=30|Location.X=490|Location.Y=858|Name=27|Designator=27|PinPropagationDelay=0.000000E+000
|RECORD=2|OwnerIndex=367|OwnerPartId=1|FormalType=1|PinConglomerate=24|PinLength=30|Location.X=550|Location.Y=858|Name=28|Designator=28|PinPropagationDelay=0.000000E+000
|RECORD=2|OwnerIndex=367|OwnerPartId=1|FormalType=1|PinConglomerate=26|PinLength=30|Location.X=490|Location.Y=848|Name=29|Designator=29|PinPropagationDelay=0.000000E+000
|RECORD=2|OwnerIndex=367|OwnerPartId=1|FormalType=1|PinConglomerate=24|PinLength=30|Location.X=550|Location.Y=848|Name=30|Designator=30|PinPropagationDelay=0.000000E+000
|RECORD=2|OwnerIndex=367|OwnerPartId=1|FormalType=1|PinConglomerate=26|PinLength=30|Location.X=490|Location.Y=838|Name=31|Designator=31|PinPropagationDelay=0.000000E+000
|RECORD=2|OwnerIndex=367|OwnerPartId=1|FormalType=1|PinConglomerate=24|PinLength=30|Location.X=550|Location.Y=838|Name=32|Designator=32|PinPropagationDelay=0.000000E+000
|RECORD=2|OwnerIndex=367|OwnerPartId=1|FormalType=1|PinConglomerate=26|PinLength=30|Location.X=490|Location.Y=828|Name=33|Designator=33|PinPropagationDelay=0.000000E+000
|RECORD=2|OwnerIndex=367|OwnerPartId=1|FormalType=1|PinConglomerate=24|PinLength=30|Location.X=550|Location.Y=828|Name=34|Designator=34|PinPropagationDelay=0.000000E+000
|RECORD=2|OwnerIndex=367|OwnerPartId=1|FormalType=1|PinConglomerate=26|PinLength=30|Location.X=490|Location.Y=818|Name=35|Designator=35|PinPropagationDelay=0.000000E+000
|RECORD=2|OwnerIndex=367|OwnerPartId=1|FormalType=1|PinConglomerate=24|PinLength=30|Location.X=550|Location.Y=818|Name=36|Designator=36|PinPropagationDelay=0.000000E+000
|RECORD=2|OwnerIndex=367|OwnerPartId=1|FormalType=1|PinConglomerate=26|PinLength=30|Location.X=490|Location.Y=808|Name=37|Designator=37|PinPropagationDelay=0.000000E+000
|RECORD=2|OwnerIndex=367|OwnerPartId=1|FormalType=1|PinConglomerate=24|PinLength=30|Location.X=550|Location.Y=808|Name=38|Designator=38|PinPropagationDelay=0.000000E+000
|RECORD=2|OwnerIndex=367|OwnerPartId=1|FormalType=1|PinConglomerate=26|PinLength=30|Location.X=490|Location.Y=798|Name=39|Designator=39|PinPropagationDelay=0.000000E+000
|RECORD=2|OwnerIndex=367|OwnerPartId=1|FormalType=1|PinConglomerate=24|PinLength=30|Location.X=550|Location.Y=798|Name=40|Designator=40|PinPropagationDelay=0.000000E+000
|RECORD=2|OwnerIndex=367|OwnerPartId=1|FormalType=1|PinConglomerate=26|PinLength=30|Location.X=490|Location.Y=788|Name=41|Designator=41|PinPropagationDelay=0.000000E+000
|RECORD=2|OwnerIndex=367|OwnerPartId=1|FormalType=1|PinConglomerate=24|PinLength=30|Location.X=550|Location.Y=788|Name=42|Designator=42|PinPropagationDelay=0.000000E+000
|RECORD=2|OwnerIndex=367|OwnerPartId=1|FormalType=1|PinConglomerate=26|PinLength=30|Location.X=490|Location.Y=778|Name=43|Designator=43|PinPropagationDelay=0.000000E+000
|RECORD=2|OwnerIndex=367|OwnerPartId=1|FormalType=1|PinConglomerate=24|PinLength=30|Location.X=550|Location.Y=778|Name=44|Designator=44|PinPropagationDelay=0.000000E+000
|RECORD=2|OwnerIndex=367|OwnerPartId=1|FormalType=1|PinConglomerate=26|PinLength=30|Location.X=490|Location.Y=768|Name=45|Designator=45|PinPropagationDelay=0.000000E+000
|RECORD=2|OwnerIndex=367|OwnerPartId=1|FormalType=1|PinConglomerate=24|PinLength=30|Location.X=550|Location.Y=768|Name=46|Designator=46|PinPropagationDelay=0.000000E+000
|RECORD=2|OwnerIndex=367|OwnerPartId=1|FormalType=1|PinConglomerate=26|PinLength=30|Location.X=490|Location.Y=758|Name=47|Designator=47|PinPropagationDelay=0.000000E+000
|RECORD=2|OwnerIndex=367|OwnerPartId=1|FormalType=1|PinConglomerate=24|PinLength=30|Location.X=550|Location.Y=758|Name=48|Designator=48|PinPropagationDelay=0.000000E+000
|RECORD=2|OwnerIndex=367|OwnerPartId=1|FormalType=1|PinConglomerate=26|PinLength=30|Location.X=490|Location.Y=748|Name=49|Designator=49|PinPropagationDelay=0.000000E+000
|RECORD=2|OwnerIndex=367|OwnerPartId=1|FormalType=1|PinConglomerate=24|PinLength=30|Location.X=550|Location.Y=748|Name=50|Designator=50|PinPropagationDelay=0.000000E+000
|RECORD=2|OwnerIndex=367|OwnerPartId=1|FormalType=1|PinConglomerate=26|PinLength=30|Location.X=490|Location.Y=738|Name=51|Designator=51|PinPropagationDelay=0.000000E+000
|RECORD=2|OwnerIndex=367|OwnerPartId=1|FormalType=1|PinConglomerate=24|PinLength=30|Location.X=550|Location.Y=738|Name=52|Designator=52|PinPropagationDelay=0.000000E+000
|RECORD=2|OwnerIndex=367|OwnerPartId=1|FormalType=1|PinConglomerate=26|PinLength=30|Location.X=490|Location.Y=728|Name=53|Designator=53|PinPropagationDelay=0.000000E+000
|RECORD=2|OwnerIndex=367|OwnerPartId=1|FormalType=1|PinConglomerate=24|PinLength=30|Location.X=550|Location.Y=728|Name=54|Designator=54|PinPropagationDelay=0.000000E+000
|RECORD=2|OwnerIndex=367|OwnerPartId=1|FormalType=1|PinConglomerate=26|PinLength=30|Location.X=490|Location.Y=718|Name=55|Designator=55|PinPropagationDelay=0.000000E+000
|RECORD=2|OwnerIndex=367|OwnerPartId=1|FormalType=1|PinConglomerate=24|PinLength=30|Location.X=550|Location.Y=718|Name=56|Designator=56|PinPropagationDelay=0.000000E+000
|RECORD=2|OwnerIndex=367|OwnerPartId=1|FormalType=1|PinConglomerate=26|PinLength=30|Location.X=490|Location.Y=708|Name=57|Designator=57|PinPropagationDelay=0.000000E+000
|RECORD=2|OwnerIndex=367|OwnerPartId=1|FormalType=1|PinConglomerate=24|PinLength=30|Location.X=550|Location.Y=708|Name=58|Designator=58|PinPropagationDelay=0.000000E+000
|RECORD=2|OwnerIndex=367|OwnerPartId=1|FormalType=1|PinConglomerate=26|PinLength=30|Location.X=490|Location.Y=698|Name=59|Designator=59|PinPropagationDelay=0.000000E+000
|RECORD=2|OwnerIndex=367|OwnerPartId=1|FormalType=1|PinConglomerate=24|PinLength=30|Location.X=550|Location.Y=698|Name=60|Designator=60|PinPropagationDelay=0.000000E+000
|RECORD=2|OwnerIndex=367|OwnerPartId=1|FormalType=1|PinConglomerate=26|PinLength=30|Location.X=490|Location.Y=688|Name=61|Designator=61|PinPropagationDelay=0.000000E+000
|RECORD=2|OwnerIndex=367|OwnerPartId=1|FormalType=1|PinConglomerate=24|PinLength=30|Location.X=550|Location.Y=688|Name=62|Designator=62|PinPropagationDelay=0.000000E+000
|RECORD=2|OwnerIndex=367|OwnerPartId=1|FormalType=1|PinConglomerate=26|PinLength=30|Location.X=490|Location.Y=678|Name=63|Designator=63|PinPropagationDelay=0.000000E+000
|RECORD=2|OwnerIndex=367|OwnerPartId=1|FormalType=1|PinConglomerate=24|PinLength=30|Location.X=550|Location.Y=678|Name=64|Designator=64|PinPropagationDelay=0.000000E+000
|RECORD=2|OwnerIndex=367|OwnerPartId=1|FormalType=1|PinConglomerate=26|PinLength=30|Location.X=490|Location.Y=668|Name=65|Designator=65|PinPropagationDelay=0.000000E+000
|RECORD=2|OwnerIndex=367|OwnerPartId=1|FormalType=1|PinConglomerate=24|PinLength=30|Location.X=550|Location.Y=668|Name=66|Designator=66|PinPropagationDelay=0.000000E+000
|RECORD=2|OwnerIndex=367|OwnerPartId=1|FormalType=1|PinConglomerate=26|PinLength=30|Location.X=490|Location.Y=658|Name=67|Designator=67|PinPropagationDelay=0.000000E+000
|RECORD=2|OwnerIndex=367|OwnerPartId=1|FormalType=1|PinConglomerate=24|PinLength=30|Location.X=550|Location.Y=658|Name=68|Designator=68|PinPropagationDelay=0.000000E+000
|RECORD=2|OwnerIndex=367|OwnerPartId=1|FormalType=1|PinConglomerate=26|PinLength=30|Location.X=490|Location.Y=648|Name=69|Designator=69|PinPropagationDelay=0.000000E+000
|RECORD=2|OwnerIndex=367|OwnerPartId=1|FormalType=1|PinConglomerate=24|PinLength=30|Location.X=550|Location.Y=648|Name=70|Designator=70|PinPropagationDelay=0.000000E+000
|RECORD=2|OwnerIndex=367|OwnerPartId=1|FormalType=1|PinConglomerate=26|PinLength=30|Location.X=490|Location.Y=638|Name=71|Designator=71|PinPropagationDelay=0.000000E+000
|RECORD=2|OwnerIndex=367|OwnerPartId=1|FormalType=1|PinConglomerate=24|PinLength=30|Location.X=550|Location.Y=638|Name=72|Designator=72|PinPropagationDelay=0.000000E+000
|RECORD=2|OwnerIndex=367|OwnerPartId=1|FormalType=1|PinConglomerate=26|PinLength=30|Location.X=490|Location.Y=628|Name=73|Designator=73|PinPropagationDelay=0.000000E+000
|RECORD=2|OwnerIndex=367|OwnerPartId=1|FormalType=1|PinConglomerate=24|PinLength=30|Location.X=550|Location.Y=628|Name=74|Designator=74|PinPropagationDelay=0.000000E+000
|RECORD=2|OwnerIndex=367|OwnerPartId=1|FormalType=1|PinConglomerate=26|PinLength=30|Location.X=490|Location.Y=618|Name=75|Designator=75|PinPropagationDelay=0.000000E+000
|RECORD=2|OwnerIndex=367|OwnerPartId=1|FormalType=1|PinConglomerate=24|PinLength=30|Location.X=550|Location.Y=618|Name=76|Designator=76|PinPropagationDelay=0.000000E+000
|RECORD=2|OwnerIndex=367|OwnerPartId=1|FormalType=1|PinConglomerate=26|PinLength=30|Location.X=490|Location.Y=608|Name=77|Designator=77|PinPropagationDelay=0.000000E+000
|RECORD=2|OwnerIndex=367|OwnerPartId=1|FormalType=1|PinConglomerate=24|PinLength=30|Location.X=550|Location.Y=608|Name=78|Designator=78|PinPropagationDelay=0.000000E+000
|RECORD=2|OwnerIndex=367|OwnerPartId=1|FormalType=1|PinConglomerate=26|PinLength=30|Location.X=490|Location.Y=598|Name=79|Designator=79|PinPropagationDelay=0.000000E+000
|RECORD=2|OwnerIndex=367|OwnerPartId=1|FormalType=1|PinConglomerate=24|PinLength=30|Location.X=550|Location.Y=598|Name=80|Designator=80|PinPropagationDelay=0.000000E+000
|RECORD=2|OwnerIndex=367|OwnerPartId=1|FormalType=1|PinConglomerate=26|PinLength=30|Location.X=490|Location.Y=588|Name=81|Designator=81|PinPropagationDelay=0.000000E+000
|RECORD=2|OwnerIndex=367|OwnerPartId=1|FormalType=1|PinConglomerate=24|PinLength=30|Location.X=550|Location.Y=588|Name=82|Designator=82|PinPropagationDelay=0.000000E+000
|RECORD=2|OwnerIndex=367|OwnerPartId=1|FormalType=1|PinConglomerate=26|PinLength=30|Location.X=490|Location.Y=578|Name=83|Designator=83|PinPropagationDelay=0.000000E+000
|RECORD=2|OwnerIndex=367|OwnerPartId=1|FormalType=1|PinConglomerate=24|PinLength=30|Location.X=550|Location.Y=578|Name=84|Designator=84|PinPropagationDelay=0.000000E+000
|RECORD=34|OwnerIndex=367|IndexInSheet=-1|OwnerPartId=-1|Location.X=490|Location.Y=998|Color=8388608|FontID=1|Text=J34|Name=Designator|ReadOnlyState=1
|RECORD=41|OwnerIndex=367|IndexInSheet=-1|OwnerPartId=-1|Location.X=490|Location.Y=558|Color=8388608|FontID=1|Text=Single FPGA Conn|Name=Comment
|RECORD=44|OwnerIndex=367
|RECORD=45|OwnerIndex=542|IndexInSheet=-1|ModelName=SingleFPGAConn|ModelType=PCBLIB|DatafileCount=1|ModelDatafileEntity0=SingleFPGAConn|ModelDatafileKind0=PCBLib|IsCurrent=T
|RECORD=46|OwnerIndex=543
|RECORD=48|OwnerIndex=543
|RECORD=1|LibReference=Single FPGA Conn|PartCount=2|DisplayModeCount=1|IndexInSheet=334|OwnerPartId=-1|Location.X=460|Location.Y=88|CurrentPartId=1|LibraryPath=*|SourceLibraryName=FPGA_CONN.SchLib|TargetFileName=*|AreaColor=11599871|Color=128|PartIDLocked=T|PinsMoveable=T|DesignItemId=Single FPGA Conn|AllPinCount=84
|RECORD=41|OwnerIndex=546|OwnerPartId=-1|Location.X=455|Location.Y=508|Color=8388608|FontID=1|IsHidden=T|Text=Digi-Key|Name=Supplier 1|ReadOnlyState=3
|RECORD=41|OwnerIndex=546|IndexInSheet=1|OwnerPartId=-1|Location.X=490|Location.Y=508|Color=8388608|FontID=1|IsHidden=T|Text=255-3246-1-ND|Name=Supplier Part Number 1|ReadOnlyState=3
|RECORD=41|OwnerIndex=546|IndexInSheet=2|OwnerPartId=-1|Location.X=490|Location.Y=58|Color=8388608|FontID=1|Text=AXK680347YG|Name=Part Number
|RECORD=14|OwnerIndex=546|IsNotAccesible=T|IndexInSheet=3|OwnerPartId=1|Location.X=490|Location.Y=78|Corner.X=550|Corner.Y=508|Color=128|AreaColor=11599871|IsSolid=T
|RECORD=2|OwnerIndex=546|OwnerPartId=1|FormalType=1|PinConglomerate=26|PinLength=30|Location.X=490|Location.Y=498|Name=1|Designator=1|PinPropagationDelay=0.000000E+000
|RECORD=2|OwnerIndex=546|OwnerPartId=1|FormalType=1|PinConglomerate=24|PinLength=30|Location.X=550|Location.Y=498|Name=2|Designator=2|PinPropagationDelay=0.000000E+000
|RECORD=2|OwnerIndex=546|OwnerPartId=1|FormalType=1|PinConglomerate=26|PinLength=30|Location.X=490|Location.Y=488|Name=3|Designator=3|PinPropagationDelay=0.000000E+000
|RECORD=2|OwnerIndex=546|OwnerPartId=1|FormalType=1|PinConglomerate=24|PinLength=30|Location.X=550|Location.Y=488|Name=4|Designator=4|PinPropagationDelay=0.000000E+000
|RECORD=2|OwnerIndex=546|OwnerPartId=1|FormalType=1|PinConglomerate=26|PinLength=30|Location.X=490|Location.Y=478|Name=5|Designator=5|PinPropagationDelay=0.000000E+000
|RECORD=2|OwnerIndex=546|OwnerPartId=1|FormalType=1|PinConglomerate=24|PinLength=30|Location.X=550|Location.Y=478|Name=6|Designator=6|PinPropagationDelay=0.000000E+000
|RECORD=2|OwnerIndex=546|OwnerPartId=1|FormalType=1|PinConglomerate=26|PinLength=30|Location.X=490|Location.Y=468|Name=7|Designator=7|PinPropagationDelay=0.000000E+000
|RECORD=2|OwnerIndex=546|OwnerPartId=1|FormalType=1|PinConglomerate=24|PinLength=30|Location.X=550|Location.Y=468|Name=8|Designator=8|PinPropagationDelay=0.000000E+000
|RECORD=2|OwnerIndex=546|OwnerPartId=1|FormalType=1|PinConglomerate=26|PinLength=30|Location.X=490|Location.Y=458|Name=9|Designator=9|PinPropagationDelay=0.000000E+000
|RECORD=2|OwnerIndex=546|OwnerPartId=1|FormalType=1|PinConglomerate=24|PinLength=30|Location.X=550|Location.Y=458|Name=10|Designator=10|PinPropagationDelay=0.000000E+000
|RECORD=2|OwnerIndex=546|OwnerPartId=1|FormalType=1|PinConglomerate=26|PinLength=30|Location.X=490|Location.Y=448|Name=11|Designator=11|PinPropagationDelay=0.000000E+000
|RECORD=2|OwnerIndex=546|OwnerPartId=1|FormalType=1|PinConglomerate=24|PinLength=30|Location.X=550|Location.Y=448|Name=12|Designator=12|PinPropagationDelay=0.000000E+000
|RECORD=2|OwnerIndex=546|OwnerPartId=1|FormalType=1|PinConglomerate=26|PinLength=30|Location.X=490|Location.Y=438|Name=13|Designator=13|PinPropagationDelay=0.000000E+000
|RECORD=2|OwnerIndex=546|OwnerPartId=1|FormalType=1|PinConglomerate=24|PinLength=30|Location.X=550|Location.Y=438|Name=14|Designator=14|PinPropagationDelay=0.000000E+000
|RECORD=2|OwnerIndex=546|OwnerPartId=1|FormalType=1|PinConglomerate=26|PinLength=30|Location.X=490|Location.Y=428|Name=15|Designator=15|PinPropagationDelay=0.000000E+000
|RECORD=2|OwnerIndex=546|OwnerPartId=1|FormalType=1|PinConglomerate=24|PinLength=30|Location.X=550|Location.Y=428|Name=16|Designator=16|PinPropagationDelay=0.000000E+000
|RECORD=2|OwnerIndex=546|OwnerPartId=1|FormalType=1|PinConglomerate=26|PinLength=30|Location.X=490|Location.Y=418|Name=17|Designator=17|PinPropagationDelay=0.000000E+000
|RECORD=2|OwnerIndex=546|OwnerPartId=1|FormalType=1|PinConglomerate=24|PinLength=30|Location.X=550|Location.Y=418|Name=18|Designator=18|PinPropagationDelay=0.000000E+000
|RECORD=2|OwnerIndex=546|OwnerPartId=1|FormalType=1|PinConglomerate=26|PinLength=30|Location.X=490|Location.Y=408|Name=19|Designator=19|PinPropagationDelay=0.000000E+000
|RECORD=2|OwnerIndex=546|OwnerPartId=1|FormalType=1|PinConglomerate=24|PinLength=30|Location.X=550|Location.Y=408|Name=20|Designator=20|PinPropagationDelay=0.000000E+000
|RECORD=2|OwnerIndex=546|OwnerPartId=1|FormalType=1|PinConglomerate=26|PinLength=30|Location.X=490|Location.Y=398|Name=21|Designator=21|PinPropagationDelay=0.000000E+000
|RECORD=2|OwnerIndex=546|OwnerPartId=1|FormalType=1|PinConglomerate=24|PinLength=30|Location.X=550|Location.Y=398|Name=22|Designator=22|PinPropagationDelay=0.000000E+000
|RECORD=2|OwnerIndex=546|OwnerPartId=1|FormalType=1|PinConglomerate=26|PinLength=30|Location.X=490|Location.Y=388|Name=23|Designator=23|PinPropagationDelay=0.000000E+000
|RECORD=2|OwnerIndex=546|OwnerPartId=1|FormalType=1|PinConglomerate=24|PinLength=30|Location.X=550|Location.Y=388|Name=24|Designator=24|PinPropagationDelay=0.000000E+000
|RECORD=2|OwnerIndex=546|OwnerPartId=1|FormalType=1|PinConglomerate=26|PinLength=30|Location.X=490|Location.Y=378|Name=25|Designator=25|PinPropagationDelay=0.000000E+000
|RECORD=2|OwnerIndex=546|OwnerPartId=1|FormalType=1|PinConglomerate=24|PinLength=30|Location.X=550|Location.Y=378|Name=26|Designator=26|PinPropagationDelay=0.000000E+000
|RECORD=2|OwnerIndex=546|OwnerPartId=1|FormalType=1|PinConglomerate=26|PinLength=30|Location.X=490|Location.Y=368|Name=27|Designator=27|PinPropagationDelay=0.000000E+000
|RECORD=2|OwnerIndex=546|OwnerPartId=1|FormalType=1|PinConglomerate=24|PinLength=30|Location.X=550|Location.Y=368|Name=28|Designator=28|PinPropagationDelay=0.000000E+000
|RECORD=2|OwnerIndex=546|OwnerPartId=1|FormalType=1|PinConglomerate=26|PinLength=30|Location.X=490|Location.Y=358|Name=29|Designator=29|PinPropagationDelay=0.000000E+000
|RECORD=2|OwnerIndex=546|OwnerPartId=1|FormalType=1|PinConglomerate=24|PinLength=30|Location.X=550|Location.Y=358|Name=30|Designator=30|PinPropagationDelay=0.000000E+000
|RECORD=2|OwnerIndex=546|OwnerPartId=1|FormalType=1|PinConglomerate=26|PinLength=30|Location.X=490|Location.Y=348|Name=31|Designator=31|PinPropagationDelay=0.000000E+000
|RECORD=2|OwnerIndex=546|OwnerPartId=1|FormalType=1|PinConglomerate=24|PinLength=30|Location.X=550|Location.Y=348|Name=32|Designator=32|PinPropagationDelay=0.000000E+000
|RECORD=2|OwnerIndex=546|OwnerPartId=1|FormalType=1|PinConglomerate=26|PinLength=30|Location.X=490|Location.Y=338|Name=33|Designator=33|PinPropagationDelay=0.000000E+000
|RECORD=2|OwnerIndex=546|OwnerPartId=1|FormalType=1|PinConglomerate=24|PinLength=30|Location.X=550|Location.Y=338|Name=34|Designator=34|PinPropagationDelay=0.000000E+000
|RECORD=2|OwnerIndex=546|OwnerPartId=1|FormalType=1|PinConglomerate=26|PinLength=30|Location.X=490|Location.Y=328|Name=35|Designator=35|PinPropagationDelay=0.000000E+000
|RECORD=2|OwnerIndex=546|OwnerPartId=1|FormalType=1|PinConglomerate=24|PinLength=30|Location.X=550|Location.Y=328|Name=36|Designator=36|PinPropagationDelay=0.000000E+000
|RECORD=2|OwnerIndex=546|OwnerPartId=1|FormalType=1|PinConglomerate=26|PinLength=30|Location.X=490|Location.Y=318|Name=37|Designator=37|PinPropagationDelay=0.000000E+000
|RECORD=2|OwnerIndex=546|OwnerPartId=1|FormalType=1|PinConglomerate=24|PinLength=30|Location.X=550|Location.Y=318|Name=38|Designator=38|PinPropagationDelay=0.000000E+000
|RECORD=2|OwnerIndex=546|OwnerPartId=1|FormalType=1|PinConglomerate=26|PinLength=30|Location.X=490|Location.Y=308|Name=39|Designator=39|PinPropagationDelay=0.000000E+000
|RECORD=2|OwnerIndex=546|OwnerPartId=1|FormalType=1|PinConglomerate=24|PinLength=30|Location.X=550|Location.Y=308|Name=40|Designator=40|PinPropagationDelay=0.000000E+000
|RECORD=2|OwnerIndex=546|OwnerPartId=1|FormalType=1|PinConglomerate=26|PinLength=30|Location.X=490|Location.Y=298|Name=41|Designator=41|PinPropagationDelay=0.000000E+000
|RECORD=2|OwnerIndex=546|OwnerPartId=1|FormalType=1|PinConglomerate=24|PinLength=30|Location.X=550|Location.Y=298|Name=42|Designator=42|PinPropagationDelay=0.000000E+000
|RECORD=2|OwnerIndex=546|OwnerPartId=1|FormalType=1|PinConglomerate=26|PinLength=30|Location.X=490|Location.Y=288|Name=43|Designator=43|PinPropagationDelay=0.000000E+000
|RECORD=2|OwnerIndex=546|OwnerPartId=1|FormalType=1|PinConglomerate=24|PinLength=30|Location.X=550|Location.Y=288|Name=44|Designator=44|PinPropagationDelay=0.000000E+000
|RECORD=2|OwnerIndex=546|OwnerPartId=1|FormalType=1|PinConglomerate=26|PinLength=30|Location.X=490|Location.Y=278|Name=45|Designator=45|PinPropagationDelay=0.000000E+000
|RECORD=2|OwnerIndex=546|OwnerPartId=1|FormalType=1|PinConglomerate=24|PinLength=30|Location.X=550|Location.Y=278|Name=46|Designator=46|PinPropagationDelay=0.000000E+000
|RECORD=2|OwnerIndex=546|OwnerPartId=1|FormalType=1|PinConglomerate=26|PinLength=30|Location.X=490|Location.Y=268|Name=47|Designator=47|PinPropagationDelay=0.000000E+000
|RECORD=2|OwnerIndex=546|OwnerPartId=1|FormalType=1|PinConglomerate=24|PinLength=30|Location.X=550|Location.Y=268|Name=48|Designator=48|PinPropagationDelay=0.000000E+000
|RECORD=2|OwnerIndex=546|OwnerPartId=1|FormalType=1|PinConglomerate=26|PinLength=30|Location.X=490|Location.Y=258|Name=49|Designator=49|PinPropagationDelay=0.000000E+000
|RECORD=2|OwnerIndex=546|OwnerPartId=1|FormalType=1|PinConglomerate=24|PinLength=30|Location.X=550|Location.Y=258|Name=50|Designator=50|PinPropagationDelay=0.000000E+000
|RECORD=2|OwnerIndex=546|OwnerPartId=1|FormalType=1|PinConglomerate=26|PinLength=30|Location.X=490|Location.Y=248|Name=51|Designator=51|PinPropagationDelay=0.000000E+000
|RECORD=2|OwnerIndex=546|OwnerPartId=1|FormalType=1|PinConglomerate=24|PinLength=30|Location.X=550|Location.Y=248|Name=52|Designator=52|PinPropagationDelay=0.000000E+000
|RECORD=2|OwnerIndex=546|OwnerPartId=1|FormalType=1|PinConglomerate=26|PinLength=30|Location.X=490|Location.Y=238|Name=53|Designator=53|PinPropagationDelay=0.000000E+000
|RECORD=2|OwnerIndex=546|OwnerPartId=1|FormalType=1|PinConglomerate=24|PinLength=30|Location.X=550|Location.Y=238|Name=54|Designator=54|PinPropagationDelay=0.000000E+000
|RECORD=2|OwnerIndex=546|OwnerPartId=1|FormalType=1|PinConglomerate=26|PinLength=30|Location.X=490|Location.Y=228|Name=55|Designator=55|PinPropagationDelay=0.000000E+000
|RECORD=2|OwnerIndex=546|OwnerPartId=1|FormalType=1|PinConglomerate=24|PinLength=30|Location.X=550|Location.Y=228|Name=56|Designator=56|PinPropagationDelay=0.000000E+000
|RECORD=2|OwnerIndex=546|OwnerPartId=1|FormalType=1|PinConglomerate=26|PinLength=30|Location.X=490|Location.Y=218|Name=57|Designator=57|PinPropagationDelay=0.000000E+000
|RECORD=2|OwnerIndex=546|OwnerPartId=1|FormalType=1|PinConglomerate=24|PinLength=30|Location.X=550|Location.Y=218|Name=58|Designator=58|PinPropagationDelay=0.000000E+000
|RECORD=2|OwnerIndex=546|OwnerPartId=1|FormalType=1|PinConglomerate=26|PinLength=30|Location.X=490|Location.Y=208|Name=59|Designator=59|PinPropagationDelay=0.000000E+000
|RECORD=2|OwnerIndex=546|OwnerPartId=1|FormalType=1|PinConglomerate=24|PinLength=30|Location.X=550|Location.Y=208|Name=60|Designator=60|PinPropagationDelay=0.000000E+000
|RECORD=2|OwnerIndex=546|OwnerPartId=1|FormalType=1|PinConglomerate=26|PinLength=30|Location.X=490|Location.Y=198|Name=61|Designator=61|PinPropagationDelay=0.000000E+000
|RECORD=2|OwnerIndex=546|OwnerPartId=1|FormalType=1|PinConglomerate=24|PinLength=30|Location.X=550|Location.Y=198|Name=62|Designator=62|PinPropagationDelay=0.000000E+000
|RECORD=2|OwnerIndex=546|OwnerPartId=1|FormalType=1|PinConglomerate=26|PinLength=30|Location.X=490|Location.Y=188|Name=63|Designator=63|PinPropagationDelay=0.000000E+000
|RECORD=2|OwnerIndex=546|OwnerPartId=1|FormalType=1|PinConglomerate=24|PinLength=30|Location.X=550|Location.Y=188|Name=64|Designator=64|PinPropagationDelay=0.000000E+000
|RECORD=2|OwnerIndex=546|OwnerPartId=1|FormalType=1|PinConglomerate=26|PinLength=30|Location.X=490|Location.Y=178|Name=65|Designator=65|PinPropagationDelay=0.000000E+000
|RECORD=2|OwnerIndex=546|OwnerPartId=1|FormalType=1|PinConglomerate=24|PinLength=30|Location.X=550|Location.Y=178|Name=66|Designator=66|PinPropagationDelay=0.000000E+000
|RECORD=2|OwnerIndex=546|OwnerPartId=1|FormalType=1|PinConglomerate=26|PinLength=30|Location.X=490|Location.Y=168|Name=67|Designator=67|PinPropagationDelay=0.000000E+000
|RECORD=2|OwnerIndex=546|OwnerPartId=1|FormalType=1|PinConglomerate=24|PinLength=30|Location.X=550|Location.Y=168|Name=68|Designator=68|PinPropagationDelay=0.000000E+000
|RECORD=2|OwnerIndex=546|OwnerPartId=1|FormalType=1|PinConglomerate=26|PinLength=30|Location.X=490|Location.Y=158|Name=69|Designator=69|PinPropagationDelay=0.000000E+000
|RECORD=2|OwnerIndex=546|OwnerPartId=1|FormalType=1|PinConglomerate=24|PinLength=30|Location.X=550|Location.Y=158|Name=70|Designator=70|PinPropagationDelay=0.000000E+000
|RECORD=2|OwnerIndex=546|OwnerPartId=1|FormalType=1|PinConglomerate=26|PinLength=30|Location.X=490|Location.Y=148|Name=71|Designator=71|PinPropagationDelay=0.000000E+000
|RECORD=2|OwnerIndex=546|OwnerPartId=1|FormalType=1|PinConglomerate=24|PinLength=30|Location.X=550|Location.Y=148|Name=72|Designator=72|PinPropagationDelay=0.000000E+000
|RECORD=2|OwnerIndex=546|OwnerPartId=1|FormalType=1|PinConglomerate=26|PinLength=30|Location.X=490|Location.Y=138|Name=73|Designator=73|PinPropagationDelay=0.000000E+000
|RECORD=2|OwnerIndex=546|OwnerPartId=1|FormalType=1|PinConglomerate=24|PinLength=30|Location.X=550|Location.Y=138|Name=74|Designator=74|PinPropagationDelay=0.000000E+000
|RECORD=2|OwnerIndex=546|OwnerPartId=1|FormalType=1|PinConglomerate=26|PinLength=30|Location.X=490|Location.Y=128|Name=75|Designator=75|PinPropagationDelay=0.000000E+000
|RECORD=2|OwnerIndex=546|OwnerPartId=1|FormalType=1|PinConglomerate=24|PinLength=30|Location.X=550|Location.Y=128|Name=76|Designator=76|PinPropagationDelay=0.000000E+000
|RECORD=2|OwnerIndex=546|OwnerPartId=1|FormalType=1|PinConglomerate=26|PinLength=30|Location.X=490|Location.Y=118|Name=77|Designator=77|PinPropagationDelay=0.000000E+000
|RECORD=2|OwnerIndex=546|OwnerPartId=1|FormalType=1|PinConglomerate=24|PinLength=30|Location.X=550|Location.Y=118|Name=78|Designator=78|PinPropagationDelay=0.000000E+000
|RECORD=2|OwnerIndex=546|OwnerPartId=1|FormalType=1|PinConglomerate=26|PinLength=30|Location.X=490|Location.Y=108|Name=79|Designator=79|PinPropagationDelay=0.000000E+000
|RECORD=2|OwnerIndex=546|OwnerPartId=1|FormalType=1|PinConglomerate=24|PinLength=30|Location.X=550|Location.Y=108|Name=80|Designator=80|PinPropagationDelay=0.000000E+000
|RECORD=2|OwnerIndex=546|OwnerPartId=1|FormalType=1|PinConglomerate=26|PinLength=30|Location.X=490|Location.Y=98|Name=81|Designator=81|PinPropagationDelay=0.000000E+000
|RECORD=2|OwnerIndex=546|OwnerPartId=1|FormalType=1|PinConglomerate=24|PinLength=30|Location.X=550|Location.Y=98|Name=82|Designator=82|PinPropagationDelay=0.000000E+000
|RECORD=2|OwnerIndex=546|OwnerPartId=1|FormalType=1|PinConglomerate=26|PinLength=30|Location.X=490|Location.Y=88|Name=83|Designator=83|PinPropagationDelay=0.000000E+000
|RECORD=2|OwnerIndex=546|OwnerPartId=1|FormalType=1|PinConglomerate=24|PinLength=30|Location.X=550|Location.Y=88|Name=84|Designator=84|PinPropagationDelay=0.000000E+000
|RECORD=34|OwnerIndex=546|IndexInSheet=-1|OwnerPartId=-1|Location.X=490|Location.Y=508|Color=8388608|FontID=1|Text=J36|Name=Designator|ReadOnlyState=1
|RECORD=41|OwnerIndex=546|IndexInSheet=-1|OwnerPartId=-1|Location.X=490|Location.Y=68|Color=8388608|FontID=1|Text=Single FPGA Conn|Name=Comment
|RECORD=44|OwnerIndex=546
|RECORD=45|OwnerIndex=721|IndexInSheet=-1|ModelName=SingleFPGAConn|ModelType=PCBLIB|DatafileCount=1|ModelDatafileEntity0=SingleFPGAConn|ModelDatafileKind0=PCBLib|IsCurrent=T
|RECORD=46|OwnerIndex=722
|RECORD=48|OwnerIndex=722
|RECORD=1|LibReference=Single FPGA Conn|PartCount=2|DisplayModeCount=1|IndexInSheet=335|OwnerPartId=-1|Location.X=1170|Location.Y=578|CurrentPartId=1|LibraryPath=*|SourceLibraryName=FPGA_CONN.SchLib|TargetFileName=*|AreaColor=11599871|Color=128|PartIDLocked=T|PinsMoveable=T|DesignItemId=Single FPGA Conn|AllPinCount=84
|RECORD=41|OwnerIndex=725|OwnerPartId=-1|Location.X=1165|Location.Y=998|Color=8388608|FontID=1|IsHidden=T|Text=Digi-Key|Name=Supplier 1|ReadOnlyState=3
|RECORD=41|OwnerIndex=725|IndexInSheet=1|OwnerPartId=-1|Location.X=1200|Location.Y=998|Color=8388608|FontID=1|IsHidden=T|Text=255-3246-1-ND|Name=Supplier Part Number 1|ReadOnlyState=3
|RECORD=41|OwnerIndex=725|IndexInSheet=2|OwnerPartId=-1|Location.X=1200|Location.Y=548|Color=8388608|FontID=1|Text=AXK680347YG|Name=Part Number
|RECORD=14|OwnerIndex=725|IsNotAccesible=T|IndexInSheet=3|OwnerPartId=1|Location.X=1200|Location.Y=568|Corner.X=1260|Corner.Y=998|Color=128|AreaColor=11599871|IsSolid=T
|RECORD=2|OwnerIndex=725|OwnerPartId=1|FormalType=1|PinConglomerate=26|PinLength=30|Location.X=1200|Location.Y=988|Name=1|Designator=1|PinPropagationDelay=0.000000E+000
|RECORD=2|OwnerIndex=725|OwnerPartId=1|FormalType=1|PinConglomerate=24|PinLength=30|Location.X=1260|Location.Y=988|Name=2|Designator=2|PinPropagationDelay=0.000000E+000
|RECORD=2|OwnerIndex=725|OwnerPartId=1|FormalType=1|PinConglomerate=26|PinLength=30|Location.X=1200|Location.Y=978|Name=3|Designator=3|PinPropagationDelay=0.000000E+000
|RECORD=2|OwnerIndex=725|OwnerPartId=1|FormalType=1|PinConglomerate=24|PinLength=30|Location.X=1260|Location.Y=978|Name=4|Designator=4|PinPropagationDelay=0.000000E+000
|RECORD=2|OwnerIndex=725|OwnerPartId=1|FormalType=1|PinConglomerate=26|PinLength=30|Location.X=1200|Location.Y=968|Name=5|Designator=5|PinPropagationDelay=0.000000E+000
|RECORD=2|OwnerIndex=725|OwnerPartId=1|FormalType=1|PinConglomerate=24|PinLength=30|Location.X=1260|Location.Y=968|Name=6|Designator=6|PinPropagationDelay=0.000000E+000
|RECORD=2|OwnerIndex=725|OwnerPartId=1|FormalType=1|PinConglomerate=26|PinLength=30|Location.X=1200|Location.Y=958|Name=7|Designator=7|PinPropagationDelay=0.000000E+000
|RECORD=2|OwnerIndex=725|OwnerPartId=1|FormalType=1|PinConglomerate=24|PinLength=30|Location.X=1260|Location.Y=958|Name=8|Designator=8|PinPropagationDelay=0.000000E+000
|RECORD=2|OwnerIndex=725|OwnerPartId=1|FormalType=1|PinConglomerate=26|PinLength=30|Location.X=1200|Location.Y=948|Name=9|Designator=9|PinPropagationDelay=0.000000E+000
|RECORD=2|OwnerIndex=725|OwnerPartId=1|FormalType=1|PinConglomerate=24|PinLength=30|Location.X=1260|Location.Y=948|Name=10|Designator=10|PinPropagationDelay=0.000000E+000
|RECORD=2|OwnerIndex=725|OwnerPartId=1|FormalType=1|PinConglomerate=26|PinLength=30|Location.X=1200|Location.Y=938|Name=11|Designator=11|PinPropagationDelay=0.000000E+000
|RECORD=2|OwnerIndex=725|OwnerPartId=1|FormalType=1|PinConglomerate=24|PinLength=30|Location.X=1260|Location.Y=938|Name=12|Designator=12|PinPropagationDelay=0.000000E+000
|RECORD=2|OwnerIndex=725|OwnerPartId=1|FormalType=1|PinConglomerate=26|PinLength=30|Location.X=1200|Location.Y=928|Name=13|Designator=13|PinPropagationDelay=0.000000E+000
|RECORD=2|OwnerIndex=725|OwnerPartId=1|FormalType=1|PinConglomerate=24|PinLength=30|Location.X=1260|Location.Y=928|Name=14|Designator=14|PinPropagationDelay=0.000000E+000
|RECORD=2|OwnerIndex=725|OwnerPartId=1|FormalType=1|PinConglomerate=26|PinLength=30|Location.X=1200|Location.Y=918|Name=15|Designator=15|PinPropagationDelay=0.000000E+000
|RECORD=2|OwnerIndex=725|OwnerPartId=1|FormalType=1|PinConglomerate=24|PinLength=30|Location.X=1260|Location.Y=918|Name=16|Designator=16|PinPropagationDelay=0.000000E+000
|RECORD=2|OwnerIndex=725|OwnerPartId=1|FormalType=1|PinConglomerate=26|PinLength=30|Location.X=1200|Location.Y=908|Name=17|Designator=17|PinPropagationDelay=0.000000E+000
|RECORD=2|OwnerIndex=725|OwnerPartId=1|FormalType=1|PinConglomerate=24|PinLength=30|Location.X=1260|Location.Y=908|Name=18|Designator=18|PinPropagationDelay=0.000000E+000
|RECORD=2|OwnerIndex=725|OwnerPartId=1|FormalType=1|PinConglomerate=26|PinLength=30|Location.X=1200|Location.Y=898|Name=19|Designator=19|PinPropagationDelay=0.000000E+000
|RECORD=2|OwnerIndex=725|OwnerPartId=1|FormalType=1|PinConglomerate=24|PinLength=30|Location.X=1260|Location.Y=898|Name=20|Designator=20|PinPropagationDelay=0.000000E+000
|RECORD=2|OwnerIndex=725|OwnerPartId=1|FormalType=1|PinConglomerate=26|PinLength=30|Location.X=1200|Location.Y=888|Name=21|Designator=21|PinPropagationDelay=0.000000E+000
|RECORD=2|OwnerIndex=725|OwnerPartId=1|FormalType=1|PinConglomerate=24|PinLength=30|Location.X=1260|Location.Y=888|Name=22|Designator=22|PinPropagationDelay=0.000000E+000
|RECORD=2|OwnerIndex=725|OwnerPartId=1|FormalType=1|PinConglomerate=26|PinLength=30|Location.X=1200|Location.Y=878|Name=23|Designator=23|PinPropagationDelay=0.000000E+000
|RECORD=2|OwnerIndex=725|OwnerPartId=1|FormalType=1|PinConglomerate=24|PinLength=30|Location.X=1260|Location.Y=878|Name=24|Designator=24|PinPropagationDelay=0.000000E+000
|RECORD=2|OwnerIndex=725|OwnerPartId=1|FormalType=1|PinConglomerate=26|PinLength=30|Location.X=1200|Location.Y=868|Name=25|Designator=25|PinPropagationDelay=0.000000E+000
|RECORD=2|OwnerIndex=725|OwnerPartId=1|FormalType=1|PinConglomerate=24|PinLength=30|Location.X=1260|Location.Y=868|Name=26|Designator=26|PinPropagationDelay=0.000000E+000
|RECORD=2|OwnerIndex=725|OwnerPartId=1|FormalType=1|PinConglomerate=26|PinLength=30|Location.X=1200|Location.Y=858|Name=27|Designator=27|PinPropagationDelay=0.000000E+000
|RECORD=2|OwnerIndex=725|OwnerPartId=1|FormalType=1|PinConglomerate=24|PinLength=30|Location.X=1260|Location.Y=858|Name=28|Designator=28|PinPropagationDelay=0.000000E+000
|RECORD=2|OwnerIndex=725|OwnerPartId=1|FormalType=1|PinConglomerate=26|PinLength=30|Location.X=1200|Location.Y=848|Name=29|Designator=29|PinPropagationDelay=0.000000E+000
|RECORD=2|OwnerIndex=725|OwnerPartId=1|FormalType=1|PinConglomerate=24|PinLength=30|Location.X=1260|Location.Y=848|Name=30|Designator=30|PinPropagationDelay=0.000000E+000
|RECORD=2|OwnerIndex=725|OwnerPartId=1|FormalType=1|PinConglomerate=26|PinLength=30|Location.X=1200|Location.Y=838|Name=31|Designator=31|PinPropagationDelay=0.000000E+000
|RECORD=2|OwnerIndex=725|OwnerPartId=1|FormalType=1|PinConglomerate=24|PinLength=30|Location.X=1260|Location.Y=838|Name=32|Designator=32|PinPropagationDelay=0.000000E+000
|RECORD=2|OwnerIndex=725|OwnerPartId=1|FormalType=1|PinConglomerate=26|PinLength=30|Location.X=1200|Location.Y=828|Name=33|Designator=33|PinPropagationDelay=0.000000E+000
|RECORD=2|OwnerIndex=725|OwnerPartId=1|FormalType=1|PinConglomerate=24|PinLength=30|Location.X=1260|Location.Y=828|Name=34|Designator=34|PinPropagationDelay=0.000000E+000
|RECORD=2|OwnerIndex=725|OwnerPartId=1|FormalType=1|PinConglomerate=26|PinLength=30|Location.X=1200|Location.Y=818|Name=35|Designator=35|PinPropagationDelay=0.000000E+000
|RECORD=2|OwnerIndex=725|OwnerPartId=1|FormalType=1|PinConglomerate=24|PinLength=30|Location.X=1260|Location.Y=818|Name=36|Designator=36|PinPropagationDelay=0.000000E+000
|RECORD=2|OwnerIndex=725|OwnerPartId=1|FormalType=1|PinConglomerate=26|PinLength=30|Location.X=1200|Location.Y=808|Name=37|Designator=37|PinPropagationDelay=0.000000E+000
|RECORD=2|OwnerIndex=725|OwnerPartId=1|FormalType=1|PinConglomerate=24|PinLength=30|Location.X=1260|Location.Y=808|Name=38|Designator=38|PinPropagationDelay=0.000000E+000
|RECORD=2|OwnerIndex=725|OwnerPartId=1|FormalType=1|PinConglomerate=26|PinLength=30|Location.X=1200|Location.Y=798|Name=39|Designator=39|PinPropagationDelay=0.000000E+000
|RECORD=2|OwnerIndex=725|OwnerPartId=1|FormalType=1|PinConglomerate=24|PinLength=30|Location.X=1260|Location.Y=798|Name=40|Designator=40|PinPropagationDelay=0.000000E+000
|RECORD=2|OwnerIndex=725|OwnerPartId=1|FormalType=1|PinConglomerate=26|PinLength=30|Location.X=1200|Location.Y=788|Name=41|Designator=41|PinPropagationDelay=0.000000E+000
|RECORD=2|OwnerIndex=725|OwnerPartId=1|FormalType=1|PinConglomerate=24|PinLength=30|Location.X=1260|Location.Y=788|Name=42|Designator=42|PinPropagationDelay=0.000000E+000
|RECORD=2|OwnerIndex=725|OwnerPartId=1|FormalType=1|PinConglomerate=26|PinLength=30|Location.X=1200|Location.Y=778|Name=43|Designator=43|PinPropagationDelay=0.000000E+000
|RECORD=2|OwnerIndex=725|OwnerPartId=1|FormalType=1|PinConglomerate=24|PinLength=30|Location.X=1260|Location.Y=778|Name=44|Designator=44|PinPropagationDelay=0.000000E+000
|RECORD=2|OwnerIndex=725|OwnerPartId=1|FormalType=1|PinConglomerate=26|PinLength=30|Location.X=1200|Location.Y=768|Name=45|Designator=45|PinPropagationDelay=0.000000E+000
|RECORD=2|OwnerIndex=725|OwnerPartId=1|FormalType=1|PinConglomerate=24|PinLength=30|Location.X=1260|Location.Y=768|Name=46|Designator=46|PinPropagationDelay=0.000000E+000
|RECORD=2|OwnerIndex=725|OwnerPartId=1|FormalType=1|PinConglomerate=26|PinLength=30|Location.X=1200|Location.Y=758|Name=47|Designator=47|PinPropagationDelay=0.000000E+000
|RECORD=2|OwnerIndex=725|OwnerPartId=1|FormalType=1|PinConglomerate=24|PinLength=30|Location.X=1260|Location.Y=758|Name=48|Designator=48|PinPropagationDelay=0.000000E+000
|RECORD=2|OwnerIndex=725|OwnerPartId=1|FormalType=1|PinConglomerate=26|PinLength=30|Location.X=1200|Location.Y=748|Name=49|Designator=49|PinPropagationDelay=0.000000E+000
|RECORD=2|OwnerIndex=725|OwnerPartId=1|FormalType=1|PinConglomerate=24|PinLength=30|Location.X=1260|Location.Y=748|Name=50|Designator=50|PinPropagationDelay=0.000000E+000
|RECORD=2|OwnerIndex=725|OwnerPartId=1|FormalType=1|PinConglomerate=26|PinLength=30|Location.X=1200|Location.Y=738|Name=51|Designator=51|PinPropagationDelay=0.000000E+000
|RECORD=2|OwnerIndex=725|OwnerPartId=1|FormalType=1|PinConglomerate=24|PinLength=30|Location.X=1260|Location.Y=738|Name=52|Designator=52|PinPropagationDelay=0.000000E+000
|RECORD=2|OwnerIndex=725|OwnerPartId=1|FormalType=1|PinConglomerate=26|PinLength=30|Location.X=1200|Location.Y=728|Name=53|Designator=53|PinPropagationDelay=0.000000E+000
|RECORD=2|OwnerIndex=725|OwnerPartId=1|FormalType=1|PinConglomerate=24|PinLength=30|Location.X=1260|Location.Y=728|Name=54|Designator=54|PinPropagationDelay=0.000000E+000
|RECORD=2|OwnerIndex=725|OwnerPartId=1|FormalType=1|PinConglomerate=26|PinLength=30|Location.X=1200|Location.Y=718|Name=55|Designator=55|PinPropagationDelay=0.000000E+000
|RECORD=2|OwnerIndex=725|OwnerPartId=1|FormalType=1|PinConglomerate=24|PinLength=30|Location.X=1260|Location.Y=718|Name=56|Designator=56|PinPropagationDelay=0.000000E+000
|RECORD=2|OwnerIndex=725|OwnerPartId=1|FormalType=1|PinConglomerate=26|PinLength=30|Location.X=1200|Location.Y=708|Name=57|Designator=57|PinPropagationDelay=0.000000E+000
|RECORD=2|OwnerIndex=725|OwnerPartId=1|FormalType=1|PinConglomerate=24|PinLength=30|Location.X=1260|Location.Y=708|Name=58|Designator=58|PinPropagationDelay=0.000000E+000
|RECORD=2|OwnerIndex=725|OwnerPartId=1|FormalType=1|PinConglomerate=26|PinLength=30|Location.X=1200|Location.Y=698|Name=59|Designator=59|PinPropagationDelay=0.000000E+000
|RECORD=2|OwnerIndex=725|OwnerPartId=1|FormalType=1|PinConglomerate=24|PinLength=30|Location.X=1260|Location.Y=698|Name=60|Designator=60|PinPropagationDelay=0.000000E+000
|RECORD=2|OwnerIndex=725|OwnerPartId=1|FormalType=1|PinConglomerate=26|PinLength=30|Location.X=1200|Location.Y=688|Name=61|Designator=61|PinPropagationDelay=0.000000E+000
|RECORD=2|OwnerIndex=725|OwnerPartId=1|FormalType=1|PinConglomerate=24|PinLength=30|Location.X=1260|Location.Y=688|Name=62|Designator=62|PinPropagationDelay=0.000000E+000
|RECORD=2|OwnerIndex=725|OwnerPartId=1|FormalType=1|PinConglomerate=26|PinLength=30|Location.X=1200|Location.Y=678|Name=63|Designator=63|PinPropagationDelay=0.000000E+000
|RECORD=2|OwnerIndex=725|OwnerPartId=1|FormalType=1|PinConglomerate=24|PinLength=30|Location.X=1260|Location.Y=678|Name=64|Designator=64|PinPropagationDelay=0.000000E+000
|RECORD=2|OwnerIndex=725|OwnerPartId=1|FormalType=1|PinConglomerate=26|PinLength=30|Location.X=1200|Location.Y=668|Name=65|Designator=65|PinPropagationDelay=0.000000E+000
|RECORD=2|OwnerIndex=725|OwnerPartId=1|FormalType=1|PinConglomerate=24|PinLength=30|Location.X=1260|Location.Y=668|Name=66|Designator=66|PinPropagationDelay=0.000000E+000
|RECORD=2|OwnerIndex=725|OwnerPartId=1|FormalType=1|PinConglomerate=26|PinLength=30|Location.X=1200|Location.Y=658|Name=67|Designator=67|PinPropagationDelay=0.000000E+000
|RECORD=2|OwnerIndex=725|OwnerPartId=1|FormalType=1|PinConglomerate=24|PinLength=30|Location.X=1260|Location.Y=658|Name=68|Designator=68|PinPropagationDelay=0.000000E+000
|RECORD=2|OwnerIndex=725|OwnerPartId=1|FormalType=1|PinConglomerate=26|PinLength=30|Location.X=1200|Location.Y=648|Name=69|Designator=69|PinPropagationDelay=0.000000E+000
|RECORD=2|OwnerIndex=725|OwnerPartId=1|FormalType=1|PinConglomerate=24|PinLength=30|Location.X=1260|Location.Y=648|Name=70|Designator=70|PinPropagationDelay=0.000000E+000
|RECORD=2|OwnerIndex=725|OwnerPartId=1|FormalType=1|PinConglomerate=26|PinLength=30|Location.X=1200|Location.Y=638|Name=71|Designator=71|PinPropagationDelay=0.000000E+000
|RECORD=2|OwnerIndex=725|OwnerPartId=1|FormalType=1|PinConglomerate=24|PinLength=30|Location.X=1260|Location.Y=638|Name=72|Designator=72|PinPropagationDelay=0.000000E+000
|RECORD=2|OwnerIndex=725|OwnerPartId=1|FormalType=1|PinConglomerate=26|PinLength=30|Location.X=1200|Location.Y=628|Name=73|Designator=73|PinPropagationDelay=0.000000E+000
|RECORD=2|OwnerIndex=725|OwnerPartId=1|FormalType=1|PinConglomerate=24|PinLength=30|Location.X=1260|Location.Y=628|Name=74|Designator=74|PinPropagationDelay=0.000000E+000
|RECORD=2|OwnerIndex=725|OwnerPartId=1|FormalType=1|PinConglomerate=26|PinLength=30|Location.X=1200|Location.Y=618|Name=75|Designator=75|PinPropagationDelay=0.000000E+000
|RECORD=2|OwnerIndex=725|OwnerPartId=1|FormalType=1|PinConglomerate=24|PinLength=30|Location.X=1260|Location.Y=618|Name=76|Designator=76|PinPropagationDelay=0.000000E+000
|RECORD=2|OwnerIndex=725|OwnerPartId=1|FormalType=1|PinConglomerate=26|PinLength=30|Location.X=1200|Location.Y=608|Name=77|Designator=77|PinPropagationDelay=0.000000E+000
|RECORD=2|OwnerIndex=725|OwnerPartId=1|FormalType=1|PinConglomerate=24|PinLength=30|Location.X=1260|Location.Y=608|Name=78|Designator=78|PinPropagationDelay=0.000000E+000
|RECORD=2|OwnerIndex=725|OwnerPartId=1|FormalType=1|PinConglomerate=26|PinLength=30|Location.X=1200|Location.Y=598|Name=79|Designator=79|PinPropagationDelay=0.000000E+000
|RECORD=2|OwnerIndex=725|OwnerPartId=1|FormalType=1|PinConglomerate=24|PinLength=30|Location.X=1260|Location.Y=598|Name=80|Designator=80|PinPropagationDelay=0.000000E+000
|RECORD=2|OwnerIndex=725|OwnerPartId=1|FormalType=1|PinConglomerate=26|PinLength=30|Location.X=1200|Location.Y=588|Name=81|Designator=81|PinPropagationDelay=0.000000E+000
|RECORD=2|OwnerIndex=725|OwnerPartId=1|FormalType=1|PinConglomerate=24|PinLength=30|Location.X=1260|Location.Y=588|Name=82|Designator=82|PinPropagationDelay=0.000000E+000
|RECORD=2|OwnerIndex=725|OwnerPartId=1|FormalType=1|PinConglomerate=26|PinLength=30|Location.X=1200|Location.Y=578|Name=83|Designator=83|PinPropagationDelay=0.000000E+000
|RECORD=2|OwnerIndex=725|OwnerPartId=1|FormalType=1|PinConglomerate=24|PinLength=30|Location.X=1260|Location.Y=578|Name=84|Designator=84|PinPropagationDelay=0.000000E+000
|RECORD=34|OwnerIndex=725|IndexInSheet=-1|OwnerPartId=-1|Location.X=1200|Location.Y=998|Color=8388608|FontID=1|Text=J35|Name=Designator|ReadOnlyState=1
|RECORD=41|OwnerIndex=725|IndexInSheet=-1|OwnerPartId=-1|Location.X=1200|Location.Y=558|Color=8388608|FontID=1|Text=Single FPGA Conn|Name=Comment
|RECORD=44|OwnerIndex=725
|RECORD=45|OwnerIndex=900|IndexInSheet=-1|ModelName=SingleFPGAConn|ModelType=PCBLIB|DatafileCount=1|ModelDatafileEntity0=SingleFPGAConn|ModelDatafileKind0=PCBLib|IsCurrent=T
|RECORD=46|OwnerIndex=901
|RECORD=48|OwnerIndex=901
|RECORD=27|IndexInSheet=336|OwnerPartId=-1|LineWidth=1|Color=8388608|LocationCount=2|X1=1170|Y1=828|X2=1060|Y2=828
|RECORD=27|IndexInSheet=337|OwnerPartId=-1|LineWidth=1|Color=8388608|LocationCount=2|X1=320|Y1=108|X2=460|Y2=108
|RECORD=27|IndexInSheet=338|OwnerPartId=-1|LineWidth=1|Color=8388608|LocationCount=2|X1=320|Y1=118|X2=460|Y2=118
|RECORD=27|IndexInSheet=339|OwnerPartId=-1|LineWidth=1|Color=8388608|LocationCount=2|X1=320|Y1=388|X2=460|Y2=388
|RECORD=27|IndexInSheet=340|OwnerPartId=-1|LineWidth=1|Color=8388608|LocationCount=2|X1=320|Y1=398|X2=460|Y2=398
|RECORD=27|IndexInSheet=341|OwnerPartId=-1|LineWidth=1|Color=8388608|LocationCount=2|X1=460|Y1=608|X2=330|Y2=608
|RECORD=27|IndexInSheet=342|OwnerPartId=-1|LineWidth=1|Color=8388608|LocationCount=2|X1=460|Y1=618|X2=330|Y2=618
|RECORD=27|IndexInSheet=343|OwnerPartId=-1|LineWidth=1|Color=8388608|LocationCount=2|X1=460|Y1=628|X2=330|Y2=628
|RECORD=27|IndexInSheet=344|OwnerPartId=-1|LineWidth=1|Color=8388608|LocationCount=2|X1=460|Y1=638|X2=330|Y2=638
|RECORD=27|IndexInSheet=345|OwnerPartId=-1|LineWidth=1|Color=8388608|LocationCount=2|X1=460|Y1=658|X2=330|Y2=658
|RECORD=27|IndexInSheet=346|OwnerPartId=-1|LineWidth=1|Color=8388608|LocationCount=2|X1=460|Y1=158|X2=400|Y2=158
|RECORD=27|IndexInSheet=347|OwnerPartId=-1|LineWidth=1|Color=8388608|LocationCount=2|X1=460|Y1=208|X2=400|Y2=208
|RECORD=27|IndexInSheet=348|OwnerPartId=-1|LineWidth=1|Color=8388608|LocationCount=2|X1=460|Y1=258|X2=400|Y2=258
|RECORD=27|IndexInSheet=349|OwnerPartId=-1|LineWidth=1|Color=8388608|LocationCount=2|X1=460|Y1=308|X2=400|Y2=308
|RECORD=27|IndexInSheet=350|OwnerPartId=-1|LineWidth=1|Color=8388608|LocationCount=2|X1=460|Y1=358|X2=400|Y2=358
|RECORD=27|IndexInSheet=351|OwnerPartId=-1|LineWidth=1|Color=8388608|LocationCount=2|X1=460|Y1=408|X2=400|Y2=408
|RECORD=27|IndexInSheet=352|OwnerPartId=-1|LineWidth=1|Color=8388608|LocationCount=9|X1=460|Y1=458|X2=400|Y2=458|X3=400|Y3=408|X4=400|Y4=358|X5=400|Y5=308|X6=400|Y6=258|X7=400|Y7=208|X8=400|Y8=158|X9=400|Y9=68
|RECORD=27|IndexInSheet=353|OwnerPartId=-1|LineWidth=1|Color=8388608|LocationCount=2|X1=460|Y1=648|X2=410|Y2=648
|RECORD=27|IndexInSheet=354|OwnerPartId=-1|LineWidth=1|Color=8388608|LocationCount=2|X1=460|Y1=698|X2=410|Y2=698
|RECORD=27|IndexInSheet=355|OwnerPartId=-1|LineWidth=1|Color=8388608|LocationCount=2|X1=460|Y1=748|X2=410|Y2=748
|RECORD=27|IndexInSheet=356|OwnerPartId=-1|LineWidth=1|Color=8388608|LocationCount=2|X1=460|Y1=798|X2=410|Y2=798
|RECORD=27|IndexInSheet=357|OwnerPartId=-1|LineWidth=1|Color=8388608|LocationCount=2|X1=460|Y1=848|X2=410|Y2=848
|RECORD=27|IndexInSheet=358|OwnerPartId=-1|LineWidth=1|Color=8388608|LocationCount=2|X1=460|Y1=898|X2=410|Y2=898
|RECORD=27|IndexInSheet=359|OwnerPartId=-1|LineWidth=1|Color=8388608|LocationCount=9|X1=460|Y1=948|X2=410|Y2=948|X3=410|Y3=898|X4=410|Y4=848|X5=410|Y5=798|X6=410|Y6=748|X7=410|Y7=698|X8=410|Y8=648|X9=410|Y9=568
|RECORD=27|IndexInSheet=360|OwnerPartId=-1|LineWidth=1|Color=8388608|LocationCount=6|X1=460|Y1=958|X2=410|Y2=958|X3=410|Y3=968|X4=410|Y4=978|X5=410|Y5=988|X6=410|Y6=1008
|RECORD=27|IndexInSheet=361|OwnerPartId=-1|LineWidth=1|Color=8388608|LocationCount=2|X1=460|Y1=968|X2=410|Y2=968
|RECORD=27|IndexInSheet=362|OwnerPartId=-1|LineWidth=1|Color=8388608|LocationCount=2|X1=460|Y1=978|X2=410|Y2=978
|RECORD=27|IndexInSheet=363|OwnerPartId=-1|LineWidth=1|Color=8388608|LocationCount=2|X1=460|Y1=988|X2=410|Y2=988
|RECORD=27|IndexInSheet=364|OwnerPartId=-1|LineWidth=1|Color=8388608|LocationCount=2|X1=580|Y1=108|X2=690|Y2=108
|RECORD=27|IndexInSheet=365|OwnerPartId=-1|LineWidth=1|Color=8388608|LocationCount=2|X1=580|Y1=118|X2=690|Y2=118
|RECORD=27|IndexInSheet=366|OwnerPartId=-1|LineWidth=1|Color=8388608|LocationCount=2|X1=580|Y1=158|X2=620|Y2=158
|RECORD=27|IndexInSheet=367|OwnerPartId=-1|LineWidth=1|Color=8388608|LocationCount=2|X1=580|Y1=208|X2=620|Y2=208
|RECORD=27|IndexInSheet=368|OwnerPartId=-1|LineWidth=1|Color=8388608|LocationCount=2|X1=580|Y1=258|X2=620|Y2=258
|RECORD=27|IndexInSheet=369|OwnerPartId=-1|LineWidth=1|Color=8388608|LocationCount=2|X1=580|Y1=308|X2=620|Y2=308
|RECORD=27|IndexInSheet=370|OwnerPartId=-1|LineWidth=1|Color=8388608|LocationCount=2|X1=580|Y1=358|X2=620|Y2=358
|RECORD=27|IndexInSheet=371|OwnerPartId=-1|LineWidth=1|Color=8388608|LocationCount=2|X1=580|Y1=408|X2=620|Y2=408
|RECORD=27|IndexInSheet=372|OwnerPartId=-1|LineWidth=1|Color=8388608|LocationCount=2|X1=580|Y1=648|X2=600|Y2=648
|RECORD=27|IndexInSheet=373|OwnerPartId=-1|LineWidth=1|Color=8388608|LocationCount=2|X1=580|Y1=698|X2=600|Y2=698
|RECORD=27|IndexInSheet=374|OwnerPartId=-1|LineWidth=1|Color=8388608|LocationCount=2|X1=580|Y1=748|X2=600|Y2=748
|RECORD=27|IndexInSheet=375|OwnerPartId=-1|LineWidth=1|Color=8388608|LocationCount=2|X1=580|Y1=798|X2=600|Y2=798
|RECORD=27|IndexInSheet=376|OwnerPartId=-1|LineWidth=1|Color=8388608|LocationCount=2|X1=640|Y1=828|X2=580|Y2=828
|RECORD=27|IndexInSheet=377|OwnerPartId=-1|LineWidth=1|Color=8388608|LocationCount=2|X1=640|Y1=838|X2=580|Y2=838
|RECORD=27|IndexInSheet=378|OwnerPartId=-1|LineWidth=1|Color=8388608|LocationCount=2|X1=580|Y1=848|X2=600|Y2=848
|RECORD=27|IndexInSheet=379|OwnerPartId=-1|LineWidth=1|Color=8388608|LocationCount=2|X1=640|Y1=888|X2=580|Y2=888
|RECORD=27|IndexInSheet=380|OwnerPartId=-1|LineWidth=1|Color=8388608|LocationCount=2|X1=580|Y1=898|X2=600|Y2=898
|RECORD=27|IndexInSheet=381|OwnerPartId=-1|LineWidth=1|Color=8388608|LocationCount=2|X1=580|Y1=968|X2=600|Y2=968
|RECORD=27|IndexInSheet=382|OwnerPartId=-1|LineWidth=1|Color=8388608|LocationCount=2|X1=580|Y1=978|X2=600|Y2=978
|RECORD=27|IndexInSheet=383|OwnerPartId=-1|LineWidth=1|Color=8388608|LocationCount=2|X1=580|Y1=988|X2=600|Y2=988
|RECORD=27|IndexInSheet=384|OwnerPartId=-1|LineWidth=1|Color=8388608|LocationCount=2|X1=1160|Y1=318|X2=1060|Y2=318
|RECORD=27|IndexInSheet=385|OwnerPartId=-1|LineWidth=1|Color=8388608|LocationCount=2|X1=1160|Y1=328|X2=1060|Y2=328
|RECORD=27|IndexInSheet=386|OwnerPartId=-1|LineWidth=1|Color=8388608|LocationCount=2|X1=1160|Y1=348|X2=1060|Y2=348
|RECORD=27|IndexInSheet=387|OwnerPartId=-1|LineWidth=1|Color=8388608|LocationCount=2|X1=1160|Y1=358|X2=1060|Y2=358
|RECORD=27|IndexInSheet=388|OwnerPartId=-1|LineWidth=1|Color=8388608|LocationCount=2|X1=1160|Y1=378|X2=1060|Y2=378
|RECORD=27|IndexInSheet=389|OwnerPartId=-1|LineWidth=1|Color=8388608|LocationCount=2|X1=1160|Y1=388|X2=1060|Y2=388
|RECORD=27|IndexInSheet=390|OwnerPartId=-1|LineWidth=1|Color=8388608|LocationCount=2|X1=1160|Y1=408|X2=1060|Y2=408
|RECORD=27|IndexInSheet=391|OwnerPartId=-1|LineWidth=1|Color=8388608|LocationCount=2|X1=1160|Y1=418|X2=1060|Y2=418
|RECORD=27|IndexInSheet=392|OwnerPartId=-1|LineWidth=1|Color=8388608|LocationCount=2|X1=1170|Y1=598|X2=1060|Y2=598
|RECORD=27|IndexInSheet=393|OwnerPartId=-1|LineWidth=1|Color=8388608|LocationCount=2|X1=1060|Y1=658|X2=1170|Y2=658
|RECORD=27|IndexInSheet=394|OwnerPartId=-1|LineWidth=1|Color=8388608|LocationCount=2|X1=1060|Y1=688|X2=1170|Y2=688
|RECORD=27|IndexInSheet=395|OwnerPartId=-1|LineWidth=1|Color=8388608|LocationCount=2|X1=1060|Y1=758|X2=1170|Y2=758
|RECORD=27|IndexInSheet=396|OwnerPartId=-1|LineWidth=1|Color=8388608|LocationCount=2|X1=1060|Y1=778|X2=1170|Y2=778
|RECORD=27|IndexInSheet=397|OwnerPartId=-1|LineWidth=1|Color=8388608|LocationCount=2|X1=1170|Y1=808|X2=1060|Y2=808
|RECORD=27|IndexInSheet=398|OwnerPartId=-1|LineWidth=1|Color=8388608|LocationCount=2|X1=1170|Y1=818|X2=1060|Y2=818
|RECORD=27|IndexInSheet=399|OwnerPartId=-1|LineWidth=1|Color=8388608|LocationCount=2|X1=1059|Y1=858|X2=1170|Y2=858
|RECORD=27|IndexInSheet=400|OwnerPartId=-1|LineWidth=1|Color=8388608|LocationCount=2|X1=1059|Y1=868|X2=1170|Y2=868
|RECORD=27|IndexInSheet=401|OwnerPartId=-1|LineWidth=1|Color=8388608|LocationCount=2|X1=1059|Y1=878|X2=1170|Y2=878
|RECORD=27|IndexInSheet=402|OwnerPartId=-1|LineWidth=1|Color=8388608|LocationCount=2|X1=1059|Y1=888|X2=1170|Y2=888
|RECORD=27|IndexInSheet=403|OwnerPartId=-1|LineWidth=1|Color=8388608|LocationCount=3|X1=1060|Y1=938|X2=1160|Y2=938|X3=1170|Y3=938
|RECORD=27|IndexInSheet=404|OwnerPartId=-1|LineWidth=1|Color=8388608|LocationCount=2|X1=1160|Y1=158|X2=1110|Y2=158
|RECORD=27|IndexInSheet=405|OwnerPartId=-1|LineWidth=1|Color=8388608|LocationCount=2|X1=1160|Y1=208|X2=1110|Y2=208
|RECORD=27|IndexInSheet=406|OwnerPartId=-1|LineWidth=1|Color=8388608|LocationCount=2|X1=1160|Y1=258|X2=1110|Y2=258
|RECORD=27|IndexInSheet=407|OwnerPartId=-1|LineWidth=1|Color=8388608|LocationCount=2|X1=1160|Y1=308|X2=1110|Y2=308
|RECORD=27|IndexInSheet=408|OwnerPartId=-1|LineWidth=1|Color=8388608|LocationCount=2|X1=1160|Y1=338|X2=1110|Y2=338
|RECORD=27|IndexInSheet=409|OwnerPartId=-1|LineWidth=1|Color=8388608|LocationCount=2|X1=1160|Y1=368|X2=1110|Y2=368
|RECORD=27|IndexInSheet=410|OwnerPartId=-1|LineWidth=1|Color=8388608|LocationCount=2|X1=1160|Y1=398|X2=1110|Y2=398
|RECORD=27|IndexInSheet=411|OwnerPartId=-1|LineWidth=1|Color=8388608|LocationCount=2|X1=1160|Y1=428|X2=1110|Y2=428
|RECORD=27|IndexInSheet=412|OwnerPartId=-1|LineWidth=1|Color=8388608|LocationCount=11|X1=1160|Y1=458|X2=1110|Y2=458|X3=1110|Y3=428|X4=1110|Y4=398|X5=1110|Y5=368|X6=1110|Y6=338|X7=1110|Y7=308|X8=1110|Y8=258|X9=1110|Y9=208|X10=1110|Y10=158|X11=1110|Y11=78
|RECORD=27|IndexInSheet=413|OwnerPartId=-1|LineWidth=1|Color=8388608|LocationCount=2|X1=1170|Y1=648|X2=1130|Y2=648
|RECORD=27|IndexInSheet=414|OwnerPartId=-1|LineWidth=1|Color=8388608|LocationCount=2|X1=1170|Y1=698|X2=1130|Y2=698
|RECORD=27|IndexInSheet=415|OwnerPartId=-1|LineWidth=1|Color=8388608|LocationCount=2|X1=1170|Y1=748|X2=1130|Y2=748
|RECORD=27|IndexInSheet=416|OwnerPartId=-1|LineWidth=1|Color=8388608|LocationCount=2|X1=1170|Y1=798|X2=1130|Y2=798
|RECORD=27|IndexInSheet=417|OwnerPartId=-1|LineWidth=1|Color=8388608|LocationCount=2|X1=1170|Y1=848|X2=1130|Y2=848
|RECORD=27|IndexInSheet=418|OwnerPartId=-1|LineWidth=1|Color=8388608|LocationCount=2|X1=1170|Y1=898|X2=1130|Y2=898
|RECORD=27|IndexInSheet=419|OwnerPartId=-1|LineWidth=1|Color=8388608|LocationCount=9|X1=1170|Y1=948|X2=1130|Y2=948|X3=1130|Y3=898|X4=1130|Y4=848|X5=1130|Y5=798|X6=1130|Y6=748|X7=1130|Y7=698|X8=1130|Y8=648|X9=1130|Y9=568
|RECORD=27|IndexInSheet=420|OwnerPartId=-1|LineWidth=1|Color=8388608|LocationCount=3|X1=1170|Y1=928|X2=1160|Y2=928|X3=1160|Y3=938
|RECORD=27|IndexInSheet=421|OwnerPartId=-1|LineWidth=1|Color=8388608|LocationCount=2|X1=1280|Y1=158|X2=1310|Y2=158
|RECORD=27|IndexInSheet=422|OwnerPartId=-1|LineWidth=1|Color=8388608|LocationCount=2|X1=1280|Y1=208|X2=1310|Y2=208
|RECORD=27|IndexInSheet=423|OwnerPartId=-1|LineWidth=1|Color=8388608|LocationCount=2|X1=1280|Y1=258|X2=1310|Y2=258
|RECORD=27|IndexInSheet=424|OwnerPartId=-1|LineWidth=1|Color=8388608|LocationCount=2|X1=1280|Y1=308|X2=1310|Y2=308
|RECORD=27|IndexInSheet=425|OwnerPartId=-1|LineWidth=1|Color=8388608|LocationCount=2|X1=1280|Y1=318|X2=1360|Y2=318
|RECORD=27|IndexInSheet=426|OwnerPartId=-1|LineWidth=1|Color=8388608|LocationCount=2|X1=1280|Y1=328|X2=1360|Y2=328
|RECORD=27|IndexInSheet=427|OwnerPartId=-1|LineWidth=1|Color=8388608|LocationCount=2|X1=1280|Y1=348|X2=1360|Y2=348
|RECORD=27|IndexInSheet=428|OwnerPartId=-1|LineWidth=1|Color=8388608|LocationCount=2|X1=1280|Y1=358|X2=1360|Y2=358
|RECORD=27|IndexInSheet=429|OwnerPartId=-1|LineWidth=1|Color=8388608|LocationCount=2|X1=1280|Y1=378|X2=1360|Y2=378
|RECORD=27|IndexInSheet=430|OwnerPartId=-1|LineWidth=1|Color=8388608|LocationCount=2|X1=1280|Y1=388|X2=1360|Y2=388
|RECORD=27|IndexInSheet=431|OwnerPartId=-1|LineWidth=1|Color=8388608|LocationCount=2|X1=1280|Y1=408|X2=1360|Y2=408
|RECORD=27|IndexInSheet=432|OwnerPartId=-1|LineWidth=1|Color=8388608|LocationCount=2|X1=1280|Y1=418|X2=1360|Y2=418
|RECORD=27|IndexInSheet=433|OwnerPartId=-1|LineWidth=1|Color=8388608|LocationCount=2|X1=1280|Y1=438|X2=1360|Y2=438
|RECORD=27|IndexInSheet=434|OwnerPartId=-1|LineWidth=1|Color=8388608|LocationCount=2|X1=1280|Y1=448|X2=1360|Y2=448
|RECORD=27|IndexInSheet=435|OwnerPartId=-1|LineWidth=1|Color=8388608|LocationCount=2|X1=1290|Y1=648|X2=1320|Y2=648
|RECORD=27|IndexInSheet=436|OwnerPartId=-1|LineWidth=1|Color=8388608|LocationCount=2|X1=1290|Y1=698|X2=1320|Y2=698
|RECORD=27|IndexInSheet=437|OwnerPartId=-1|LineWidth=1|Color=8388608|LocationCount=2|X1=1290|Y1=748|X2=1320|Y2=748
|RECORD=27|IndexInSheet=438|OwnerPartId=-1|LineWidth=1|Color=8388608|LocationCount=2|X1=1290|Y1=798|X2=1320|Y2=798
|RECORD=27|IndexInSheet=439|OwnerPartId=-1|LineWidth=1|Color=8388608|LocationCount=2|X1=1290|Y1=848|X2=1320|Y2=848
|RECORD=27|IndexInSheet=440|OwnerPartId=-1|LineWidth=1|Color=8388608|LocationCount=2|X1=1290|Y1=898|X2=1320|Y2=898
|RECORD=27|IndexInSheet=441|OwnerPartId=-1|LineWidth=1|Color=8388608|LocationCount=2|X1=1350|Y1=958|X2=1290|Y2=958
|RECORD=27|IndexInSheet=442|OwnerPartId=-1|LineWidth=1|Color=8388608|LocationCount=9|X1=580|Y1=948|X2=600|Y2=948|X3=600|Y3=898|X4=600|Y4=848|X5=600|Y5=798|X6=600|Y6=748|X7=600|Y7=698|X8=600|Y8=648|X9=600|Y9=568
|RECORD=27|IndexInSheet=443|OwnerPartId=-1|LineWidth=1|Color=8388608|LocationCount=6|X1=580|Y1=958|X2=600|Y2=958|X3=600|Y3=968|X4=600|Y4=978|X5=600|Y5=988|X6=600|Y6=1008
|RECORD=27|IndexInSheet=444|OwnerPartId=-1|LineWidth=1|Color=8388608|LocationCount=2|X1=1290|Y1=598|X2=1350|Y2=598
|RECORD=27|IndexInSheet=445|OwnerPartId=-1|LineWidth=1|Color=8388608|LocationCount=2|X1=1350|Y1=628|X2=1290|Y2=628
|RECORD=27|IndexInSheet=446|OwnerPartId=-1|LineWidth=1|Color=8388608|LocationCount=2|X1=1350|Y1=638|X2=1290|Y2=638
|RECORD=27|IndexInSheet=447|OwnerPartId=-1|LineWidth=1|Color=8388608|LocationCount=2|X1=1350|Y1=858|X2=1290|Y2=858
|RECORD=27|IndexInSheet=448|OwnerPartId=-1|LineWidth=1|Color=8388608|LocationCount=2|X1=1350|Y1=868|X2=1290|Y2=868
|RECORD=27|IndexInSheet=449|OwnerPartId=-1|LineWidth=1|Color=8388608|LocationCount=9|X1=580|Y1=458|X2=620|Y2=458|X3=620|Y3=408|X4=620|Y4=358|X5=620|Y5=308|X6=620|Y6=258|X7=620|Y7=208|X8=620|Y8=158|X9=620|Y9=68
|RECORD=27|IndexInSheet=450|OwnerPartId=-1|LineWidth=1|Color=8388608|LocationCount=7|X1=1280|Y1=458|X2=1310|Y2=458|X3=1310|Y3=308|X4=1310|Y4=258|X5=1310|Y5=208|X6=1310|Y6=158|X7=1310|Y7=78
|RECORD=27|IndexInSheet=451|OwnerPartId=-1|LineWidth=1|Color=8388608|LocationCount=2|X1=1170|Y1=728|X2=1060|Y2=728
|RECORD=27|IndexInSheet=452|OwnerPartId=-1|LineWidth=1|Color=8388608|LocationCount=2|X1=460|Y1=498|X2=318|Y2=498
|RECORD=27|IndexInSheet=453|OwnerPartId=-1|LineWidth=1|Color=8388608|LocationCount=2|X1=580|Y1=498|X2=690|Y2=498
|RECORD=27|IndexInSheet=454|OwnerPartId=-1|LineWidth=1|Color=8388608|LocationCount=2|X1=1170|Y1=608|X2=1060|Y2=608
|RECORD=27|IndexInSheet=455|OwnerPartId=-1|LineWidth=1|Color=8388608|LocationCount=2|X1=1170|Y1=638|X2=1061|Y2=638
|RECORD=27|IndexInSheet=456|OwnerPartId=-1|LineWidth=1|Color=8388608|LocationCount=2|X1=460|Y1=478|X2=319|Y2=478
|RECORD=27|IndexInSheet=457|OwnerPartId=-1|LineWidth=1|Color=8388608|LocationCount=2|X1=460|Y1=448|X2=319|Y2=448
|RECORD=27|IndexInSheet=458|OwnerPartId=-1|LineWidth=1|Color=8388608|LocationCount=2|X1=460|Y1=468|X2=319|Y2=468
|RECORD=27|IndexInSheet=459|OwnerPartId=-1|LineWidth=1|Color=8388608|LocationCount=2|X1=580|Y1=448|X2=690|Y2=448
|RECORD=27|IndexInSheet=460|OwnerPartId=-1|LineWidth=1|Color=8388608|LocationCount=2|X1=580|Y1=438|X2=690|Y2=438
|RECORD=27|IndexInSheet=461|OwnerPartId=-1|LineWidth=1|Color=8388608|LocationCount=2|X1=580|Y1=428|X2=690|Y2=428
|RECORD=27|IndexInSheet=462|OwnerPartId=-1|LineWidth=1|Color=8388608|LocationCount=2|X1=691|Y1=418|X2=580|Y2=418
|RECORD=27|IndexInSheet=463|OwnerPartId=-1|LineWidth=1|Color=8388608|LocationCount=2|X1=1170|Y1=918|X2=1059|Y2=918
|RECORD=27|IndexInSheet=464|OwnerPartId=-1|LineWidth=1|Color=8388608|LocationCount=2|X1=1170|Y1=908|X2=1059|Y2=908
|RECORD=27|IndexInSheet=465|OwnerPartId=-1|LineWidth=1|Color=8388608|LocationCount=2|X1=1290|Y1=918|X2=1352|Y2=918
|RECORD=27|IndexInSheet=466|OwnerPartId=-1|LineWidth=1|Color=8388608|LocationCount=2|X1=1290|Y1=908|X2=1352|Y2=908
|RECORD=27|IndexInSheet=467|OwnerPartId=-1|LineWidth=1|Color=8388608|LocationCount=2|X1=320|Y1=338|X2=460|Y2=338
|RECORD=27|IndexInSheet=468|OwnerPartId=-1|LineWidth=1|Color=8388608|LocationCount=2|X1=320|Y1=348|X2=460|Y2=348
|RECORD=27|IndexInSheet=469|OwnerPartId=-1|LineWidth=1|Color=8388608|LocationCount=2|X1=320|Y1=328|X2=460|Y2=328
|RECORD=27|IndexInSheet=470|OwnerPartId=-1|LineWidth=1|Color=8388608|LocationCount=2|X1=320|Y1=318|X2=460|Y2=318
|RECORD=27|IndexInSheet=471|OwnerPartId=-1|LineWidth=1|Color=8388608|LocationCount=2|X1=320|Y1=298|X2=460|Y2=298
|RECORD=27|IndexInSheet=472|OwnerPartId=-1|LineWidth=1|Color=8388608|LocationCount=2|X1=320|Y1=288|X2=460|Y2=288
|RECORD=27|IndexInSheet=473|OwnerPartId=-1|LineWidth=1|Color=8388608|LocationCount=2|X1=460|Y1=278|X2=320|Y2=278
|RECORD=27|IndexInSheet=474|OwnerPartId=-1|LineWidth=1|Color=8388608|LocationCount=2|X1=320|Y1=268|X2=460|Y2=268
|RECORD=27|IndexInSheet=475|OwnerPartId=-1|LineWidth=1|Color=8388608|LocationCount=2|X1=691|Y1=348|X2=580|Y2=348
|RECORD=27|IndexInSheet=476|OwnerPartId=-1|LineWidth=1|Color=8388608|LocationCount=2|X1=691|Y1=338|X2=580|Y2=338
|RECORD=27|IndexInSheet=477|OwnerPartId=-1|LineWidth=1|Color=8388608|LocationCount=2|X1=691|Y1=328|X2=580|Y2=328
|RECORD=27|IndexInSheet=478|OwnerPartId=-1|LineWidth=1|Color=8388608|LocationCount=2|X1=691|Y1=318|X2=580|Y2=318
|RECORD=27|IndexInSheet=479|OwnerPartId=-1|LineWidth=1|Color=8388608|LocationCount=2|X1=691|Y1=298|X2=580|Y2=298
|RECORD=27|IndexInSheet=480|OwnerPartId=-1|LineWidth=1|Color=8388608|LocationCount=2|X1=691|Y1=288|X2=580|Y2=288
|RECORD=27|IndexInSheet=481|OwnerPartId=-1|LineWidth=1|Color=8388608|LocationCount=2|X1=691|Y1=278|X2=580|Y2=278
|RECORD=27|IndexInSheet=482|OwnerPartId=-1|LineWidth=1|Color=8388608|LocationCount=2|X1=691|Y1=268|X2=580|Y2=268
|RECORD=27|IndexInSheet=483|OwnerPartId=-1|LineWidth=1|Color=8388608|LocationCount=2|X1=691|Y1=778|X2=580|Y2=778
|RECORD=27|IndexInSheet=484|OwnerPartId=-1|LineWidth=1|Color=8388608|LocationCount=9|X1=1290|Y1=948|X2=1320|Y2=948|X3=1320|Y3=898|X4=1320|Y4=848|X5=1320|Y5=798|X6=1320|Y6=748|X7=1320|Y7=698|X8=1320|Y8=648|X9=1320|Y9=568
|RECORD=1|LibReference=Single FPGA Conn|PartCount=2|DisplayModeCount=1|IndexInSheet=485|OwnerPartId=-1|Location.X=1160|Location.Y=88|CurrentPartId=1|LibraryPath=*|SourceLibraryName=FPGA_CONN.SchLib|TargetFileName=*|AreaColor=11599871|Color=128|PartIDLocked=T|PinsMoveable=T|DesignItemId=Single FPGA Conn|AllPinCount=84
|RECORD=41|OwnerIndex=1053|OwnerPartId=-1|Location.X=1155|Location.Y=508|Color=8388608|FontID=1|IsHidden=T|Text=Digi-Key|Name=Supplier 1|ReadOnlyState=3
|RECORD=41|OwnerIndex=1053|IndexInSheet=1|OwnerPartId=-1|Location.X=1190|Location.Y=508|Color=8388608|FontID=1|IsHidden=T|Text=255-3246-1-ND|Name=Supplier Part Number 1|ReadOnlyState=3
|RECORD=41|OwnerIndex=1053|IndexInSheet=2|OwnerPartId=-1|Location.X=1190|Location.Y=58|Color=8388608|FontID=1|Text=AXK680347YG|Name=Part Number
|RECORD=14|OwnerIndex=1053|IsNotAccesible=T|IndexInSheet=3|OwnerPartId=1|Location.X=1190|Location.Y=78|Corner.X=1250|Corner.Y=508|Color=128|AreaColor=11599871|IsSolid=T
|RECORD=2|OwnerIndex=1053|OwnerPartId=1|FormalType=1|PinConglomerate=26|PinLength=30|Location.X=1190|Location.Y=498|Name=1|Designator=1|PinPropagationDelay=0.000000E+000
|RECORD=2|OwnerIndex=1053|OwnerPartId=1|FormalType=1|PinConglomerate=24|PinLength=30|Location.X=1250|Location.Y=498|Name=2|Designator=2|PinPropagationDelay=0.000000E+000
|RECORD=2|OwnerIndex=1053|OwnerPartId=1|FormalType=1|PinConglomerate=26|PinLength=30|Location.X=1190|Location.Y=488|Name=3|Designator=3|PinPropagationDelay=0.000000E+000
|RECORD=2|OwnerIndex=1053|OwnerPartId=1|FormalType=1|PinConglomerate=24|PinLength=30|Location.X=1250|Location.Y=488|Name=4|Designator=4|PinPropagationDelay=0.000000E+000
|RECORD=2|OwnerIndex=1053|OwnerPartId=1|FormalType=1|PinConglomerate=26|PinLength=30|Location.X=1190|Location.Y=478|Name=5|Designator=5|PinPropagationDelay=0.000000E+000
|RECORD=2|OwnerIndex=1053|OwnerPartId=1|FormalType=1|PinConglomerate=24|PinLength=30|Location.X=1250|Location.Y=478|Name=6|Designator=6|PinPropagationDelay=0.000000E+000
|RECORD=2|OwnerIndex=1053|OwnerPartId=1|FormalType=1|PinConglomerate=26|PinLength=30|Location.X=1190|Location.Y=468|Name=7|Designator=7|PinPropagationDelay=0.000000E+000
|RECORD=2|OwnerIndex=1053|OwnerPartId=1|FormalType=1|PinConglomerate=24|PinLength=30|Location.X=1250|Location.Y=468|Name=8|Designator=8|PinPropagationDelay=0.000000E+000
|RECORD=2|OwnerIndex=1053|OwnerPartId=1|FormalType=1|PinConglomerate=26|PinLength=30|Location.X=1190|Location.Y=458|Name=9|Designator=9|PinPropagationDelay=0.000000E+000
|RECORD=2|OwnerIndex=1053|OwnerPartId=1|FormalType=1|PinConglomerate=24|PinLength=30|Location.X=1250|Location.Y=458|Name=10|Designator=10|PinPropagationDelay=0.000000E+000
|RECORD=2|OwnerIndex=1053|OwnerPartId=1|FormalType=1|PinConglomerate=26|PinLength=30|Location.X=1190|Location.Y=448|Name=11|Designator=11|PinPropagationDelay=0.000000E+000
|RECORD=2|OwnerIndex=1053|OwnerPartId=1|FormalType=1|PinConglomerate=24|PinLength=30|Location.X=1250|Location.Y=448|Name=12|Designator=12|PinPropagationDelay=0.000000E+000
|RECORD=2|OwnerIndex=1053|OwnerPartId=1|FormalType=1|PinConglomerate=26|PinLength=30|Location.X=1190|Location.Y=438|Name=13|Designator=13|PinPropagationDelay=0.000000E+000
|RECORD=2|OwnerIndex=1053|OwnerPartId=1|FormalType=1|PinConglomerate=24|PinLength=30|Location.X=1250|Location.Y=438|Name=14|Designator=14|PinPropagationDelay=0.000000E+000
|RECORD=2|OwnerIndex=1053|OwnerPartId=1|FormalType=1|PinConglomerate=26|PinLength=30|Location.X=1190|Location.Y=428|Name=15|Designator=15|PinPropagationDelay=0.000000E+000
|RECORD=2|OwnerIndex=1053|OwnerPartId=1|FormalType=1|PinConglomerate=24|PinLength=30|Location.X=1250|Location.Y=428|Name=16|Designator=16|PinPropagationDelay=0.000000E+000
|RECORD=2|OwnerIndex=1053|OwnerPartId=1|FormalType=1|PinConglomerate=26|PinLength=30|Location.X=1190|Location.Y=418|Name=17|Designator=17|PinPropagationDelay=0.000000E+000
|RECORD=2|OwnerIndex=1053|OwnerPartId=1|FormalType=1|PinConglomerate=24|PinLength=30|Location.X=1250|Location.Y=418|Name=18|Designator=18|PinPropagationDelay=0.000000E+000
|RECORD=2|OwnerIndex=1053|OwnerPartId=1|FormalType=1|PinConglomerate=26|PinLength=30|Location.X=1190|Location.Y=408|Name=19|Designator=19|PinPropagationDelay=0.000000E+000
|RECORD=2|OwnerIndex=1053|OwnerPartId=1|FormalType=1|PinConglomerate=24|PinLength=30|Location.X=1250|Location.Y=408|Name=20|Designator=20|PinPropagationDelay=0.000000E+000
|RECORD=2|OwnerIndex=1053|OwnerPartId=1|FormalType=1|PinConglomerate=26|PinLength=30|Location.X=1190|Location.Y=398|Name=21|Designator=21|PinPropagationDelay=0.000000E+000
|RECORD=2|OwnerIndex=1053|OwnerPartId=1|FormalType=1|PinConglomerate=24|PinLength=30|Location.X=1250|Location.Y=398|Name=22|Designator=22|PinPropagationDelay=0.000000E+000
|RECORD=2|OwnerIndex=1053|OwnerPartId=1|FormalType=1|PinConglomerate=26|PinLength=30|Location.X=1190|Location.Y=388|Name=23|Designator=23|PinPropagationDelay=0.000000E+000
|RECORD=2|OwnerIndex=1053|OwnerPartId=1|FormalType=1|PinConglomerate=24|PinLength=30|Location.X=1250|Location.Y=388|Name=24|Designator=24|PinPropagationDelay=0.000000E+000
|RECORD=2|OwnerIndex=1053|OwnerPartId=1|FormalType=1|PinConglomerate=26|PinLength=30|Location.X=1190|Location.Y=378|Name=25|Designator=25|PinPropagationDelay=0.000000E+000
|RECORD=2|OwnerIndex=1053|OwnerPartId=1|FormalType=1|PinConglomerate=24|PinLength=30|Location.X=1250|Location.Y=378|Name=26|Designator=26|PinPropagationDelay=0.000000E+000
|RECORD=2|OwnerIndex=1053|OwnerPartId=1|FormalType=1|PinConglomerate=26|PinLength=30|Location.X=1190|Location.Y=368|Name=27|Designator=27|PinPropagationDelay=0.000000E+000
|RECORD=2|OwnerIndex=1053|OwnerPartId=1|FormalType=1|PinConglomerate=24|PinLength=30|Location.X=1250|Location.Y=368|Name=28|Designator=28|PinPropagationDelay=0.000000E+000
|RECORD=2|OwnerIndex=1053|OwnerPartId=1|FormalType=1|PinConglomerate=26|PinLength=30|Location.X=1190|Location.Y=358|Name=29|Designator=29|PinPropagationDelay=0.000000E+000
|RECORD=2|OwnerIndex=1053|OwnerPartId=1|FormalType=1|PinConglomerate=24|PinLength=30|Location.X=1250|Location.Y=358|Name=30|Designator=30|PinPropagationDelay=0.000000E+000
|RECORD=2|OwnerIndex=1053|OwnerPartId=1|FormalType=1|PinConglomerate=26|PinLength=30|Location.X=1190|Location.Y=348|Name=31|Designator=31|PinPropagationDelay=0.000000E+000
|RECORD=2|OwnerIndex=1053|OwnerPartId=1|FormalType=1|PinConglomerate=24|PinLength=30|Location.X=1250|Location.Y=348|Name=32|Designator=32|PinPropagationDelay=0.000000E+000
|RECORD=2|OwnerIndex=1053|OwnerPartId=1|FormalType=1|PinConglomerate=26|PinLength=30|Location.X=1190|Location.Y=338|Name=33|Designator=33|PinPropagationDelay=0.000000E+000
|RECORD=2|OwnerIndex=1053|OwnerPartId=1|FormalType=1|PinConglomerate=24|PinLength=30|Location.X=1250|Location.Y=338|Name=34|Designator=34|PinPropagationDelay=0.000000E+000
|RECORD=2|OwnerIndex=1053|OwnerPartId=1|FormalType=1|PinConglomerate=26|PinLength=30|Location.X=1190|Location.Y=328|Name=35|Designator=35|PinPropagationDelay=0.000000E+000
|RECORD=2|OwnerIndex=1053|OwnerPartId=1|FormalType=1|PinConglomerate=24|PinLength=30|Location.X=1250|Location.Y=328|Name=36|Designator=36|PinPropagationDelay=0.000000E+000
|RECORD=2|OwnerIndex=1053|OwnerPartId=1|FormalType=1|PinConglomerate=26|PinLength=30|Location.X=1190|Location.Y=318|Name=37|Designator=37|PinPropagationDelay=0.000000E+000
|RECORD=2|OwnerIndex=1053|OwnerPartId=1|FormalType=1|PinConglomerate=24|PinLength=30|Location.X=1250|Location.Y=318|Name=38|Designator=38|PinPropagationDelay=0.000000E+000
|RECORD=2|OwnerIndex=1053|OwnerPartId=1|FormalType=1|PinConglomerate=26|PinLength=30|Location.X=1190|Location.Y=308|Name=39|Designator=39|PinPropagationDelay=0.000000E+000
|RECORD=2|OwnerIndex=1053|OwnerPartId=1|FormalType=1|PinConglomerate=24|PinLength=30|Location.X=1250|Location.Y=308|Name=40|Designator=40|PinPropagationDelay=0.000000E+000
|RECORD=2|OwnerIndex=1053|OwnerPartId=1|FormalType=1|PinConglomerate=26|PinLength=30|Location.X=1190|Location.Y=298|Name=41|Designator=41|PinPropagationDelay=0.000000E+000
|RECORD=2|OwnerIndex=1053|OwnerPartId=1|FormalType=1|PinConglomerate=24|PinLength=30|Location.X=1250|Location.Y=298|Name=42|Designator=42|PinPropagationDelay=0.000000E+000
|RECORD=2|OwnerIndex=1053|OwnerPartId=1|FormalType=1|PinConglomerate=26|PinLength=30|Location.X=1190|Location.Y=288|Name=43|Designator=43|PinPropagationDelay=0.000000E+000
|RECORD=2|OwnerIndex=1053|OwnerPartId=1|FormalType=1|PinConglomerate=24|PinLength=30|Location.X=1250|Location.Y=288|Name=44|Designator=44|PinPropagationDelay=0.000000E+000
|RECORD=2|OwnerIndex=1053|OwnerPartId=1|FormalType=1|PinConglomerate=26|PinLength=30|Location.X=1190|Location.Y=278|Name=45|Designator=45|PinPropagationDelay=0.000000E+000
|RECORD=2|OwnerIndex=1053|OwnerPartId=1|FormalType=1|PinConglomerate=24|PinLength=30|Location.X=1250|Location.Y=278|Name=46|Designator=46|PinPropagationDelay=0.000000E+000
|RECORD=2|OwnerIndex=1053|OwnerPartId=1|FormalType=1|PinConglomerate=26|PinLength=30|Location.X=1190|Location.Y=268|Name=47|Designator=47|PinPropagationDelay=0.000000E+000
|RECORD=2|OwnerIndex=1053|OwnerPartId=1|FormalType=1|PinConglomerate=24|PinLength=30|Location.X=1250|Location.Y=268|Name=48|Designator=48|PinPropagationDelay=0.000000E+000
|RECORD=2|OwnerIndex=1053|OwnerPartId=1|FormalType=1|PinConglomerate=26|PinLength=30|Location.X=1190|Location.Y=258|Name=49|Designator=49|PinPropagationDelay=0.000000E+000
|RECORD=2|OwnerIndex=1053|OwnerPartId=1|FormalType=1|PinConglomerate=24|PinLength=30|Location.X=1250|Location.Y=258|Name=50|Designator=50|PinPropagationDelay=0.000000E+000
|RECORD=2|OwnerIndex=1053|OwnerPartId=1|FormalType=1|PinConglomerate=26|PinLength=30|Location.X=1190|Location.Y=248|Name=51|Designator=51|PinPropagationDelay=0.000000E+000
|RECORD=2|OwnerIndex=1053|OwnerPartId=1|FormalType=1|PinConglomerate=24|PinLength=30|Location.X=1250|Location.Y=248|Name=52|Designator=52|PinPropagationDelay=0.000000E+000
|RECORD=2|OwnerIndex=1053|OwnerPartId=1|FormalType=1|PinConglomerate=26|PinLength=30|Location.X=1190|Location.Y=238|Name=53|Designator=53|PinPropagationDelay=0.000000E+000
|RECORD=2|OwnerIndex=1053|OwnerPartId=1|FormalType=1|PinConglomerate=24|PinLength=30|Location.X=1250|Location.Y=238|Name=54|Designator=54|PinPropagationDelay=0.000000E+000
|RECORD=2|OwnerIndex=1053|OwnerPartId=1|FormalType=1|PinConglomerate=26|PinLength=30|Location.X=1190|Location.Y=228|Name=55|Designator=55|PinPropagationDelay=0.000000E+000
|RECORD=2|OwnerIndex=1053|OwnerPartId=1|FormalType=1|PinConglomerate=24|PinLength=30|Location.X=1250|Location.Y=228|Name=56|Designator=56|PinPropagationDelay=0.000000E+000
|RECORD=2|OwnerIndex=1053|OwnerPartId=1|FormalType=1|PinConglomerate=26|PinLength=30|Location.X=1190|Location.Y=218|Name=57|Designator=57|PinPropagationDelay=0.000000E+000
|RECORD=2|OwnerIndex=1053|OwnerPartId=1|FormalType=1|PinConglomerate=24|PinLength=30|Location.X=1250|Location.Y=218|Name=58|Designator=58|PinPropagationDelay=0.000000E+000
|RECORD=2|OwnerIndex=1053|OwnerPartId=1|FormalType=1|PinConglomerate=26|PinLength=30|Location.X=1190|Location.Y=208|Name=59|Designator=59|PinPropagationDelay=0.000000E+000
|RECORD=2|OwnerIndex=1053|OwnerPartId=1|FormalType=1|PinConglomerate=24|PinLength=30|Location.X=1250|Location.Y=208|Name=60|Designator=60|PinPropagationDelay=0.000000E+000
|RECORD=2|OwnerIndex=1053|OwnerPartId=1|FormalType=1|PinConglomerate=26|PinLength=30|Location.X=1190|Location.Y=198|Name=61|Designator=61|PinPropagationDelay=0.000000E+000
|RECORD=2|OwnerIndex=1053|OwnerPartId=1|FormalType=1|PinConglomerate=24|PinLength=30|Location.X=1250|Location.Y=198|Name=62|Designator=62|PinPropagationDelay=0.000000E+000
|RECORD=2|OwnerIndex=1053|OwnerPartId=1|FormalType=1|PinConglomerate=26|PinLength=30|Location.X=1190|Location.Y=188|Name=63|Designator=63|PinPropagationDelay=0.000000E+000
|RECORD=2|OwnerIndex=1053|OwnerPartId=1|FormalType=1|PinConglomerate=24|PinLength=30|Location.X=1250|Location.Y=188|Name=64|Designator=64|PinPropagationDelay=0.000000E+000
|RECORD=2|OwnerIndex=1053|OwnerPartId=1|FormalType=1|PinConglomerate=26|PinLength=30|Location.X=1190|Location.Y=178|Name=65|Designator=65|PinPropagationDelay=0.000000E+000
|RECORD=2|OwnerIndex=1053|OwnerPartId=1|FormalType=1|PinConglomerate=24|PinLength=30|Location.X=1250|Location.Y=178|Name=66|Designator=66|PinPropagationDelay=0.000000E+000
|RECORD=2|OwnerIndex=1053|OwnerPartId=1|FormalType=1|PinConglomerate=26|PinLength=30|Location.X=1190|Location.Y=168|Name=67|Designator=67|PinPropagationDelay=0.000000E+000
|RECORD=2|OwnerIndex=1053|OwnerPartId=1|FormalType=1|PinConglomerate=24|PinLength=30|Location.X=1250|Location.Y=168|Name=68|Designator=68|PinPropagationDelay=0.000000E+000
|RECORD=2|OwnerIndex=1053|OwnerPartId=1|FormalType=1|PinConglomerate=26|PinLength=30|Location.X=1190|Location.Y=158|Name=69|Designator=69|PinPropagationDelay=0.000000E+000
|RECORD=2|OwnerIndex=1053|OwnerPartId=1|FormalType=1|PinConglomerate=24|PinLength=30|Location.X=1250|Location.Y=158|Name=70|Designator=70|PinPropagationDelay=0.000000E+000
|RECORD=2|OwnerIndex=1053|OwnerPartId=1|FormalType=1|PinConglomerate=26|PinLength=30|Location.X=1190|Location.Y=148|Name=71|Designator=71|PinPropagationDelay=0.000000E+000
|RECORD=2|OwnerIndex=1053|OwnerPartId=1|FormalType=1|PinConglomerate=24|PinLength=30|Location.X=1250|Location.Y=148|Name=72|Designator=72|PinPropagationDelay=0.000000E+000
|RECORD=2|OwnerIndex=1053|OwnerPartId=1|FormalType=1|PinConglomerate=26|PinLength=30|Location.X=1190|Location.Y=138|Name=73|Designator=73|PinPropagationDelay=0.000000E+000
|RECORD=2|OwnerIndex=1053|OwnerPartId=1|FormalType=1|PinConglomerate=24|PinLength=30|Location.X=1250|Location.Y=138|Name=74|Designator=74|PinPropagationDelay=0.000000E+000
|RECORD=2|OwnerIndex=1053|OwnerPartId=1|FormalType=1|PinConglomerate=26|PinLength=30|Location.X=1190|Location.Y=128|Name=75|Designator=75|PinPropagationDelay=0.000000E+000
|RECORD=2|OwnerIndex=1053|OwnerPartId=1|FormalType=1|PinConglomerate=24|PinLength=30|Location.X=1250|Location.Y=128|Name=76|Designator=76|PinPropagationDelay=0.000000E+000
|RECORD=2|OwnerIndex=1053|OwnerPartId=1|FormalType=1|PinConglomerate=26|PinLength=30|Location.X=1190|Location.Y=118|Name=77|Designator=77|PinPropagationDelay=0.000000E+000
|RECORD=2|OwnerIndex=1053|OwnerPartId=1|FormalType=1|PinConglomerate=24|PinLength=30|Location.X=1250|Location.Y=118|Name=78|Designator=78|PinPropagationDelay=0.000000E+000
|RECORD=2|OwnerIndex=1053|OwnerPartId=1|FormalType=1|PinConglomerate=26|PinLength=30|Location.X=1190|Location.Y=108|Name=79|Designator=79|PinPropagationDelay=0.000000E+000
|RECORD=2|OwnerIndex=1053|OwnerPartId=1|FormalType=1|PinConglomerate=24|PinLength=30|Location.X=1250|Location.Y=108|Name=80|Designator=80|PinPropagationDelay=0.000000E+000
|RECORD=2|OwnerIndex=1053|OwnerPartId=1|FormalType=1|PinConglomerate=26|PinLength=30|Location.X=1190|Location.Y=98|Name=81|Designator=81|PinPropagationDelay=0.000000E+000
|RECORD=2|OwnerIndex=1053|OwnerPartId=1|FormalType=1|PinConglomerate=24|PinLength=30|Location.X=1250|Location.Y=98|Name=82|Designator=82|PinPropagationDelay=0.000000E+000
|RECORD=2|OwnerIndex=1053|OwnerPartId=1|FormalType=1|PinConglomerate=26|PinLength=30|Location.X=1190|Location.Y=88|Name=83|Designator=83|PinPropagationDelay=0.000000E+000
|RECORD=2|OwnerIndex=1053|OwnerPartId=1|FormalType=1|PinConglomerate=24|PinLength=30|Location.X=1250|Location.Y=88|Name=84|Designator=84|PinPropagationDelay=0.000000E+000
|RECORD=34|OwnerIndex=1053|IndexInSheet=-1|OwnerPartId=-1|Location.X=1190|Location.Y=508|Color=8388608|FontID=1|Text=J37|Name=Designator|ReadOnlyState=1
|RECORD=41|OwnerIndex=1053|IndexInSheet=-1|OwnerPartId=-1|Location.X=1190|Location.Y=68|Color=8388608|FontID=1|Text=Single FPGA Conn|Name=Comment
|RECORD=44|OwnerIndex=1053
|RECORD=45|OwnerIndex=1228|IndexInSheet=-1|ModelName=SingleFPGAConn|ModelType=PCBLIB|DatafileCount=1|ModelDatafileEntity0=SingleFPGAConn|ModelDatafileKind0=PCBLib|IsCurrent=T
|RECORD=46|OwnerIndex=1229
|RECORD=48|OwnerIndex=1229
|RECORD=29|IndexInSheet=-1|OwnerPartId=-1|Location.X=400|Location.Y=158|Color=128
|RECORD=29|IndexInSheet=-1|OwnerPartId=-1|Location.X=400|Location.Y=208|Color=128
|RECORD=29|IndexInSheet=-1|OwnerPartId=-1|Location.X=400|Location.Y=258|Color=128
|RECORD=29|IndexInSheet=-1|OwnerPartId=-1|Location.X=400|Location.Y=308|Color=128
|RECORD=29|IndexInSheet=-1|OwnerPartId=-1|Location.X=400|Location.Y=358|Color=128
|RECORD=29|IndexInSheet=-1|OwnerPartId=-1|Location.X=400|Location.Y=408|Color=128
|RECORD=29|IndexInSheet=-1|OwnerPartId=-1|Location.X=410|Location.Y=648|Color=128
|RECORD=29|IndexInSheet=-1|OwnerPartId=-1|Location.X=410|Location.Y=698|Color=128
|RECORD=29|IndexInSheet=-1|OwnerPartId=-1|Location.X=410|Location.Y=748|Color=128
|RECORD=29|IndexInSheet=-1|OwnerPartId=-1|Location.X=410|Location.Y=798|Color=128
|RECORD=29|IndexInSheet=-1|OwnerPartId=-1|Location.X=410|Location.Y=848|Color=128
|RECORD=29|IndexInSheet=-1|OwnerPartId=-1|Location.X=410|Location.Y=898|Color=128
|RECORD=29|IndexInSheet=-1|OwnerPartId=-1|Location.X=410|Location.Y=968|Color=128
|RECORD=29|IndexInSheet=-1|OwnerPartId=-1|Location.X=410|Location.Y=978|Color=128
|RECORD=29|IndexInSheet=-1|OwnerPartId=-1|Location.X=410|Location.Y=988|Color=128
|RECORD=29|IndexInSheet=-1|OwnerPartId=-1|Location.X=600|Location.Y=648|Color=128
|RECORD=29|IndexInSheet=-1|OwnerPartId=-1|Location.X=600|Location.Y=698|Color=128
|RECORD=29|IndexInSheet=-1|OwnerPartId=-1|Location.X=600|Location.Y=748|Color=128
|RECORD=29|IndexInSheet=-1|OwnerPartId=-1|Location.X=600|Location.Y=798|Color=128
|RECORD=29|IndexInSheet=-1|OwnerPartId=-1|Location.X=600|Location.Y=848|Color=128
|RECORD=29|IndexInSheet=-1|OwnerPartId=-1|Location.X=600|Location.Y=898|Color=128
|RECORD=29|IndexInSheet=-1|OwnerPartId=-1|Location.X=600|Location.Y=968|Color=128
|RECORD=29|IndexInSheet=-1|OwnerPartId=-1|Location.X=600|Location.Y=978|Color=128
|RECORD=29|IndexInSheet=-1|OwnerPartId=-1|Location.X=600|Location.Y=988|Color=128
|RECORD=29|IndexInSheet=-1|OwnerPartId=-1|Location.X=620|Location.Y=158|Color=128
|RECORD=29|IndexInSheet=-1|OwnerPartId=-1|Location.X=620|Location.Y=208|Color=128
|RECORD=29|IndexInSheet=-1|OwnerPartId=-1|Location.X=620|Location.Y=258|Color=128
|RECORD=29|IndexInSheet=-1|OwnerPartId=-1|Location.X=620|Location.Y=308|Color=128
|RECORD=29|IndexInSheet=-1|OwnerPartId=-1|Location.X=620|Location.Y=358|Color=128
|RECORD=29|IndexInSheet=-1|OwnerPartId=-1|Location.X=620|Location.Y=408|Color=128
|RECORD=29|IndexInSheet=-1|OwnerPartId=-1|Location.X=1110|Location.Y=158|Color=128
|RECORD=29|IndexInSheet=-1|OwnerPartId=-1|Location.X=1110|Location.Y=208|Color=128
|RECORD=29|IndexInSheet=-1|OwnerPartId=-1|Location.X=1110|Location.Y=258|Color=128
|RECORD=29|IndexInSheet=-1|OwnerPartId=-1|Location.X=1110|Location.Y=308|Color=128
|RECORD=29|IndexInSheet=-1|OwnerPartId=-1|Location.X=1110|Location.Y=338|Color=128
|RECORD=29|IndexInSheet=-1|OwnerPartId=-1|Location.X=1110|Location.Y=368|Color=128
|RECORD=29|IndexInSheet=-1|OwnerPartId=-1|Location.X=1110|Location.Y=398|Color=128
|RECORD=29|IndexInSheet=-1|OwnerPartId=-1|Location.X=1110|Location.Y=428|Color=128
|RECORD=29|IndexInSheet=-1|OwnerPartId=-1|Location.X=1130|Location.Y=648|Color=128
|RECORD=29|IndexInSheet=-1|OwnerPartId=-1|Location.X=1130|Location.Y=698|Color=128
|RECORD=29|IndexInSheet=-1|OwnerPartId=-1|Location.X=1130|Location.Y=748|Color=128
|RECORD=29|IndexInSheet=-1|OwnerPartId=-1|Location.X=1130|Location.Y=798|Color=128
|RECORD=29|IndexInSheet=-1|OwnerPartId=-1|Location.X=1130|Location.Y=848|Color=128
|RECORD=29|IndexInSheet=-1|OwnerPartId=-1|Location.X=1130|Location.Y=898|Color=128
|RECORD=29|IndexInSheet=-1|OwnerPartId=-1|Location.X=1160|Location.Y=938|Color=128
|RECORD=29|IndexInSheet=-1|OwnerPartId=-1|Location.X=1310|Location.Y=158|Color=128
|RECORD=29|IndexInSheet=-1|OwnerPartId=-1|Location.X=1310|Location.Y=208|Color=128
|RECORD=29|IndexInSheet=-1|OwnerPartId=-1|Location.X=1310|Location.Y=258|Color=128
|RECORD=29|IndexInSheet=-1|OwnerPartId=-1|Location.X=1310|Location.Y=308|Color=128
|RECORD=29|IndexInSheet=-1|OwnerPartId=-1|Location.X=1320|Location.Y=648|Color=128
|RECORD=29|IndexInSheet=-1|OwnerPartId=-1|Location.X=1320|Location.Y=698|Color=128
|RECORD=29|IndexInSheet=-1|OwnerPartId=-1|Location.X=1320|Location.Y=748|Color=128
|RECORD=29|IndexInSheet=-1|OwnerPartId=-1|Location.X=1320|Location.Y=798|Color=128
|RECORD=29|IndexInSheet=-1|OwnerPartId=-1|Location.X=1320|Location.Y=848|Color=128
|RECORD=29|IndexInSheet=-1|OwnerPartId=-1|Location.X=1320|Location.Y=898|Color=128